(kicad_pcb
	(version 20260206)
	(generator "pcbnew")
	(generator_version "10.0")
	(general
		(thickness 1.6)
		(legacy_teardrops no)
	)
	(paper "A4")
	(layers
		(0 "F.Cu" signal "TOP")
		(4 "In1.Cu" signal "L2VCC")
		(6 "In2.Cu" signal "L3GND")
		(2 "B.Cu" signal "BOTTOM")
		(9 "F.Adhes" user "F.Adhesive")
		(11 "B.Adhes" user "B.Adhesive")
		(13 "F.Paste" user "Package Geometry/Pastemask Top")
		(15 "B.Paste" user "Package Geometry/Pastemask Bottom")
		(5 "F.SilkS" user "Ref Des/Silkscreen Top")
		(7 "B.SilkS" user "Ref Des/Silkscreen Bottom")
		(1 "F.Mask" user "Board Geometry/Soldermask Top")
		(3 "B.Mask" user "Board Geometry/Soldermask Bottom")
		(17 "Dwgs.User" user "User.Drawings")
		(19 "Cmts.User" user "User.Comments")
		(21 "Eco1.User" user "User.Eco1")
		(23 "Eco2.User" user "User.Eco2")
		(25 "Edge.Cuts" user "Board Geometry/Outline")
		(27 "Margin" user)
		(31 "F.CrtYd" user "Package Geometry/Place Bound Top")
		(29 "B.CrtYd" user "Package Geometry/Place Bound Bottom")
		(35 "F.Fab" user "Ref Des/Assembly Top")
		(33 "B.Fab" user "Ref Des/Assembly Bottom")
	)
	(setup
		(pad_to_mask_clearance 0)
		(allow_soldermask_bridges_in_footprints no)
		(tenting
			(front yes)
			(back yes)
		)
		(covering
			(front no)
			(back no)
		)
		(plugging
			(front no)
			(back no)
		)
		(capping no)
		(filling no)
		(pcbplotparams
			(layerselection 0x00000000_00000000_55555555_5755f5ff)
			(plot_on_all_layers_selection 0x00000000_00000000_00000000_00000000)
			(disableapertmacros no)
			(usegerberextensions no)
			(usegerberattributes yes)
			(usegerberadvancedattributes yes)
			(creategerberjobfile yes)
			(dashed_line_dash_ratio 12)
			(dashed_line_gap_ratio 3)
			(svgprecision 4)
			(plotframeref no)
			(mode 1)
			(useauxorigin no)
			(pdf_front_fp_property_popups yes)
			(pdf_back_fp_property_popups yes)
			(pdf_metadata yes)
			(pdf_single_document no)
			(dxfpolygonmode yes)
			(dxfimperialunits yes)
			(dxfusepcbnewfont yes)
			(psnegative no)
			(psa4output no)
			(plot_black_and_white yes)
			(sketchpadsonfab no)
			(plotpadnumbers no)
			(hidednponfab no)
			(sketchdnponfab yes)
			(crossoutdnponfab yes)
			(subtractmaskfromsilk no)
			(outputformat 1)
			(mirror no)
			(drillshape 1)
			(scaleselection 1)
			(outputdirectory "")
		)
	)
	(footprint ""
		(layer "F.Cu")
		(at 77.499972 -1.400048)
		(property "Reference" "GF2"
			(at 0 0 0)
			(layer "F.SilkS")
			(hide yes)
			(effects
				(font
					(size 1.27 1.27)
				)
			)
		)
		(property "Value" "GF-PCIE-164P-4-GP"
			(at -70.358 -9.0932 0)
			(unlocked yes)
			(layer "F.Fab")
			(hide yes)
			(effects
				(font
					(size 1.016 1.016)
					(thickness 0.1524)
				)
			)
		)
		(property "Device Type" "GF-PCIE-164P-4"
			(at -70.358 -10.6172 0)
			(unlocked yes)
			(layer "F.Fab")
			(hide yes)
			(effects
				(font
					(size 1.016 1.016)
					(thickness 0.1524)
				)
			)
		)
		(duplicate_pad_numbers_are_jumpers no)
		(fp_rect
			(start -73.8886 2.032)
			(end 13.8938 -6.223)
			(stroke
				(width 0)
				(type default)
			)
			(fill no)
			(layer "B.CrtYd")
		)
		(fp_rect
			(start -73.8886 2.032)
			(end 13.8938 -6.223)
			(stroke
				(width 0)
				(type default)
			)
			(fill no)
			(layer "F.CrtYd")
		)
		(fp_rect
			(start -73.8886 2.032)
			(end 13.8938 -6.223)
			(stroke
				(width 0)
				(type default)
			)
			(fill no)
			(layer "B.Fab")
		)
		(fp_rect
			(start -73.8886 2.032)
			(end 13.8938 -6.223)
			(stroke
				(width 0)
				(type default)
			)
			(fill no)
			(layer "F.Fab")
		)
		(fp_text user "02 Do not mirror"
			(at -39.116 3.6068 0)
			(unlocked yes)
			(layer "F.Fab")
			(effects
				(font
					(size 1.016 1.016)
					(thickness 0.1524)
				)
				(justify left)
			)
		)
		(pad "A1" smd rect
			(at 11.500104 -2.5908)
			(size 0.7112 3.2004)
			(layers "F.Cu" "F.Mask" "F.Paste")
			(net "BOARD_PRSNT#")
		)
		(pad "A2" smd rect
			(at 10.500106 -2.0955)
			(size 0.7112 4.191)
			(layers "F.Cu" "F.Mask" "F.Paste")
			(net "P12V")
		)
		(pad "A3" smd rect
			(at 9.500108 -2.0955)
			(size 0.7112 4.191)
			(layers "F.Cu" "F.Mask" "F.Paste")
			(net "P12V")
		)
		(pad "A4" smd rect
			(at 8.50011 -2.0955)
			(size 0.7112 4.191)
			(layers "F.Cu" "F.Mask" "F.Paste")
			(net "GND")
		)
		(pad "A5" smd rect
			(at 7.500112 -2.0955)
			(size 0.7112 4.191)
			(layers "F.Cu" "F.Mask" "F.Paste")
			(net "SLOT_ID0")
		)
		(pad "A6" smd rect
			(at 6.500114 -2.0955)
			(size 0.7112 4.191)
			(layers "F.Cu" "F.Mask" "F.Paste")
			(net "SLOT_ID1")
		)
		(pad "A7" smd rect
			(at 5.500116 -2.0955)
			(size 0.7112 4.191)
			(layers "F.Cu" "F.Mask" "F.Paste")
			(net "CPU_TXD")
		)
		(pad "A8" smd rect
			(at 4.500118 -2.0955)
			(size 0.7112 4.191)
			(layers "F.Cu" "F.Mask" "F.Paste")
			(net "CPU_RXD")
		)
		(pad "A9" smd rect
			(at 3.50012 -2.0955)
			(size 0.7112 4.191)
			(layers "F.Cu" "F.Mask" "F.Paste")
			(net "SLOT_ID2")
		)
		(pad "A10" smd rect
			(at 2.500122 -2.0955)
			(size 0.7112 4.191)
			(layers "F.Cu" "F.Mask" "F.Paste")
			(net "SLOT_ID3")
		)
		(pad "A11" smd rect
			(at 1.500124 -2.0955)
			(size 0.7112 4.191)
			(layers "F.Cu" "F.Mask" "F.Paste")
			(net "PCIE_RESET#")
		)
		(pad "A12" smd rect
			(at -1.500124 -2.0955)
			(size 0.7112 4.191)
			(layers "F.Cu" "F.Mask" "F.Paste")
			(net "GND")
		)
		(pad "A13" smd rect
			(at -2.500122 -2.0955)
			(size 0.7112 4.191)
			(layers "F.Cu" "F.Mask" "F.Paste")
			(net "CLK_100M_PCIE_SAS_C_P")
		)
		(pad "A14" smd rect
			(at -3.50012 -2.0955)
			(size 0.7112 4.191)
			(layers "F.Cu" "F.Mask" "F.Paste")
			(net "CLK_100M_PCIE_SAS_C_N")
		)
		(pad "A15" smd rect
			(at -4.500118 -2.0955)
			(size 0.7112 4.191)
			(layers "F.Cu" "F.Mask" "F.Paste")
			(net "GND")
		)
		(pad "A16" smd rect
			(at -5.500116 -2.0955)
			(size 0.7112 4.191)
			(layers "F.Cu" "F.Mask" "F.Paste")
			(net "GND")
		)
		(pad "A17" smd rect
			(at -6.500114 -2.0955)
			(size 0.7112 4.191)
			(layers "F.Cu" "F.Mask" "F.Paste")
			(net "P2E_CPU_SAS_RX_DP0")
		)
		(pad "A18" smd rect
			(at -7.500112 -2.0955)
			(size 0.7112 4.191)
			(layers "F.Cu" "F.Mask" "F.Paste")
			(net "P2E_CPU_SAS_RX_DN0")
		)
		(pad "A19" smd rect
			(at -8.50011 -2.0955)
			(size 0.7112 4.191)
			(layers "F.Cu" "F.Mask" "F.Paste")
			(net "GND")
		)
		(pad "A20" smd rect
			(at -9.500108 -2.0955)
			(size 0.7112 4.191)
			(layers "F.Cu" "F.Mask" "F.Paste")
			(net "GND")
		)
		(pad "A21" smd rect
			(at -10.500106 -2.0955)
			(size 0.7112 4.191)
			(layers "F.Cu" "F.Mask" "F.Paste")
			(net "P2E_CPU_SAS_RX_DP1")
		)
		(pad "A22" smd rect
			(at -11.500104 -2.0955)
			(size 0.7112 4.191)
			(layers "F.Cu" "F.Mask" "F.Paste")
			(net "P2E_CPU_SAS_RX_DN1")
		)
		(pad "A23" smd rect
			(at -12.500102 -2.0955)
			(size 0.7112 4.191)
			(layers "F.Cu" "F.Mask" "F.Paste")
			(net "GND")
		)
		(pad "A24" smd rect
			(at -13.5001 -2.0955)
			(size 0.7112 4.191)
			(layers "F.Cu" "F.Mask" "F.Paste")
			(net "GND")
		)
		(pad "A25" smd rect
			(at -14.500098 -2.0955)
			(size 0.7112 4.191)
			(layers "F.Cu" "F.Mask" "F.Paste")
			(net "P2E_CPU_SAS_RX_DP2")
		)
		(pad "A26" smd rect
			(at -15.500096 -2.0955)
			(size 0.7112 4.191)
			(layers "F.Cu" "F.Mask" "F.Paste")
			(net "P2E_CPU_SAS_RX_DN2")
		)
		(pad "A27" smd rect
			(at -16.500094 -2.0955)
			(size 0.7112 4.191)
			(layers "F.Cu" "F.Mask" "F.Paste")
			(net "GND")
		)
		(pad "A28" smd rect
			(at -17.500092 -2.0955)
			(size 0.7112 4.191)
			(layers "F.Cu" "F.Mask" "F.Paste")
			(net "GND")
		)
		(pad "A29" smd rect
			(at -18.50009 -2.0955)
			(size 0.7112 4.191)
			(layers "F.Cu" "F.Mask" "F.Paste")
			(net "P2E_CPU_SAS_RX_DP3")
		)
		(pad "A30" smd rect
			(at -19.500088 -2.0955)
			(size 0.7112 4.191)
			(layers "F.Cu" "F.Mask" "F.Paste")
			(net "P2E_CPU_SAS_RX_DN3")
		)
		(pad "A31" smd rect
			(at -20.500086 -2.0955)
			(size 0.7112 4.191)
			(layers "F.Cu" "F.Mask" "F.Paste")
			(net "GND")
		)
		(pad "A32" smd rect
			(at -21.500084 -2.0955)
			(size 0.7112 4.191)
			(layers "F.Cu" "F.Mask" "F.Paste")
			(net "GND")
		)
		(pad "A33" smd rect
			(at -22.500082 -2.0955)
			(size 0.7112 4.191)
			(layers "F.Cu" "F.Mask" "F.Paste")
			(net "SATA2_RX_C_DP0")
		)
		(pad "A34" smd rect
			(at -23.50008 -2.0955)
			(size 0.7112 4.191)
			(layers "F.Cu" "F.Mask" "F.Paste")
			(net "SATA2_RX_C_DN0")
		)
		(pad "A35" smd rect
			(at -24.500078 -2.0955)
			(size 0.7112 4.191)
			(layers "F.Cu" "F.Mask" "F.Paste")
			(net "GND")
		)
		(pad "A36" smd rect
			(at -25.500076 -2.0955)
			(size 0.7112 4.191)
			(layers "F.Cu" "F.Mask" "F.Paste")
			(net "GND")
		)
		(pad "A37" smd rect
			(at -26.500074 -2.0955)
			(size 0.7112 4.191)
			(layers "F.Cu" "F.Mask" "F.Paste")
			(net "PCIE_RSVD_A37")
		)
		(pad "A38" smd rect
			(at -27.500072 -2.0955)
			(size 0.7112 4.191)
			(layers "F.Cu" "F.Mask" "F.Paste")
			(net "PCIE_RSVD_A38")
		)
		(pad "A39" smd rect
			(at -28.50007 -2.0955)
			(size 0.7112 4.191)
			(layers "F.Cu" "F.Mask" "F.Paste")
			(net "GND")
		)
		(pad "A40" smd rect
			(at -29.500068 -2.0955)
			(size 0.7112 4.191)
			(layers "F.Cu" "F.Mask" "F.Paste")
			(net "GND")
		)
		(pad "A41" smd rect
			(at -30.500066 -2.0955)
			(size 0.7112 4.191)
			(layers "F.Cu" "F.Mask" "F.Paste")
			(net "PCIE_RSVD_A41")
		)
		(pad "A42" smd rect
			(at -31.500064 -2.0955)
			(size 0.7112 4.191)
			(layers "F.Cu" "F.Mask" "F.Paste")
			(net "GBE_SMBALRT_R#")
		)
		(pad "A43" smd rect
			(at -32.500062 -2.0955)
			(size 0.7112 4.191)
			(layers "F.Cu" "F.Mask" "F.Paste")
			(net "GND")
		)
		(pad "A44" smd rect
			(at -33.50006 -2.0955)
			(size 0.7112 4.191)
			(layers "F.Cu" "F.Mask" "F.Paste")
			(net "GND")
		)
		(pad "A45" smd rect
			(at -34.500058 -2.0955)
			(size 0.7112 4.191)
			(layers "F.Cu" "F.Mask" "F.Paste")
			(net "CPU_GBE_RX_C_DP0")
		)
		(pad "A46" smd rect
			(at -35.500056 -2.0955)
			(size 0.7112 4.191)
			(layers "F.Cu" "F.Mask" "F.Paste")
			(net "CPU_GBE_RX_C_DN0")
		)
		(pad "A47" smd rect
			(at -36.500054 -2.0955)
			(size 0.7112 4.191)
			(layers "F.Cu" "F.Mask" "F.Paste")
			(net "GND")
		)
		(pad "A48" smd rect
			(at -37.500052 -2.0955)
			(size 0.7112 4.191)
			(layers "F.Cu" "F.Mask" "F.Paste")
			(net "GND")
		)
		(pad "A49" smd rect
			(at -38.50005 -2.0955)
			(size 0.7112 4.191)
			(layers "F.Cu" "F.Mask" "F.Paste")
			(net "P2E_CPU_SAS_RX_DP4")
		)
		(pad "A50" smd rect
			(at -39.500048 -2.0955)
			(size 0.7112 4.191)
			(layers "F.Cu" "F.Mask" "F.Paste")
			(net "P2E_CPU_SAS_RX_DN4")
		)
		(pad "A51" smd rect
			(at -40.500046 -2.0955)
			(size 0.7112 4.191)
			(layers "F.Cu" "F.Mask" "F.Paste")
			(net "GND")
		)
		(pad "A52" smd rect
			(at -41.500044 -2.0955)
			(size 0.7112 4.191)
			(layers "F.Cu" "F.Mask" "F.Paste")
			(net "GND")
		)
		(pad "A53" smd rect
			(at -42.500042 -2.0955)
			(size 0.7112 4.191)
			(layers "F.Cu" "F.Mask" "F.Paste")
			(net "P2E_CPU_SAS_RX_DP5")
		)
		(pad "A54" smd rect
			(at -43.50004 -2.0955)
			(size 0.7112 4.191)
			(layers "F.Cu" "F.Mask" "F.Paste")
			(net "P2E_CPU_SAS_RX_DN5")
		)
		(pad "A55" smd rect
			(at -44.500038 -2.0955)
			(size 0.7112 4.191)
			(layers "F.Cu" "F.Mask" "F.Paste")
			(net "GND")
		)
		(pad "A56" smd rect
			(at -45.500036 -2.0955)
			(size 0.7112 4.191)
			(layers "F.Cu" "F.Mask" "F.Paste")
			(net "GND")
		)
		(pad "A57" smd rect
			(at -46.500034 -2.0955)
			(size 0.7112 4.191)
			(layers "F.Cu" "F.Mask" "F.Paste")
			(net "P2E_CPU_SAS_RX_DP6")
		)
		(pad "A58" smd rect
			(at -47.500032 -2.0955)
			(size 0.7112 4.191)
			(layers "F.Cu" "F.Mask" "F.Paste")
			(net "P2E_CPU_SAS_RX_DN6")
		)
		(pad "A59" smd rect
			(at -48.50003 -2.0955)
			(size 0.7112 4.191)
			(layers "F.Cu" "F.Mask" "F.Paste")
			(net "GND")
		)
		(pad "A60" smd rect
			(at -49.500028 -2.0955)
			(size 0.7112 4.191)
			(layers "F.Cu" "F.Mask" "F.Paste")
			(net "GND")
		)
		(pad "A61" smd rect
			(at -50.500026 -2.0955)
			(size 0.7112 4.191)
			(layers "F.Cu" "F.Mask" "F.Paste")
			(net "P2E_CPU_SAS_RX_DP7")
		)
		(pad "A62" smd rect
			(at -51.500024 -2.0955)
			(size 0.7112 4.191)
			(layers "F.Cu" "F.Mask" "F.Paste")
			(net "P2E_CPU_SAS_RX_DN7")
		)
		(pad "A63" smd rect
			(at -52.500022 -2.0955)
			(size 0.7112 4.191)
			(layers "F.Cu" "F.Mask" "F.Paste")
			(net "GND")
		)
		(pad "A64" smd rect
			(at -53.50002 -2.0955)
			(size 0.7112 4.191)
			(layers "F.Cu" "F.Mask" "F.Paste")
			(net "GND")
		)
		(pad "A65" smd rect
			(at -54.500018 -2.0955)
			(size 0.7112 4.191)
			(layers "F.Cu" "F.Mask" "F.Paste")
			(net "P2E_CPU_ETH10G_RX_DP8")
		)
		(pad "A66" smd rect
			(at -55.500016 -2.0955)
			(size 0.7112 4.191)
			(layers "F.Cu" "F.Mask" "F.Paste")
			(net "P2E_CPU_ETH10G_RX_DN8")
		)
		(pad "A67" smd rect
			(at -56.500014 -2.0955)
			(size 0.7112 4.191)
			(layers "F.Cu" "F.Mask" "F.Paste")
			(net "GND")
		)
		(pad "A68" smd rect
			(at -57.500012 -2.0955)
			(size 0.7112 4.191)
			(layers "F.Cu" "F.Mask" "F.Paste")
			(net "GND")
		)
		(pad "A69" smd rect
			(at -58.50001 -2.0955)
			(size 0.7112 4.191)
			(layers "F.Cu" "F.Mask" "F.Paste")
			(net "P2E_CPU_ETH10G_RX_DP9")
		)
		(pad "A70" smd rect
			(at -59.500008 -2.0955)
			(size 0.7112 4.191)
			(layers "F.Cu" "F.Mask" "F.Paste")
			(net "P2E_CPU_ETH10G_RX_DN9")
		)
		(pad "A71" smd rect
			(at -60.500006 -2.0955)
			(size 0.7112 4.191)
			(layers "F.Cu" "F.Mask" "F.Paste")
			(net "GND")
		)
		(pad "A72" smd rect
			(at -61.500004 -2.0955)
			(size 0.7112 4.191)
			(layers "F.Cu" "F.Mask" "F.Paste")
			(net "GND")
		)
		(pad "A73" smd rect
			(at -62.500002 -2.0955)
			(size 0.7112 4.191)
			(layers "F.Cu" "F.Mask" "F.Paste")
			(net "P2E_CPU_ETH10G_RX_DP10")
		)
		(pad "A74" smd rect
			(at -63.5 -2.0955)
			(size 0.7112 4.191)
			(layers "F.Cu" "F.Mask" "F.Paste")
			(net "P2E_CPU_ETH10G_RX_DN10")
		)
		(pad "A75" smd rect
			(at -64.499998 -2.0955)
			(size 0.7112 4.191)
			(layers "F.Cu" "F.Mask" "F.Paste")
			(net "GND")
		)
		(pad "A76" smd rect
			(at -65.499996 -2.0955)
			(size 0.7112 4.191)
			(layers "F.Cu" "F.Mask" "F.Paste")
			(net "GND")
		)
		(pad "A77" smd rect
			(at -66.499994 -2.0955)
			(size 0.7112 4.191)
			(layers "F.Cu" "F.Mask" "F.Paste")
			(net "P2E_CPU_ETH10G_RX_DP11")
		)
		(pad "A78" smd rect
			(at -67.499992 -2.0955)
			(size 0.7112 4.191)
			(layers "F.Cu" "F.Mask" "F.Paste")
			(net "P2E_CPU_ETH10G_RX_DN11")
		)
		(pad "A79" smd rect
			(at -68.49999 -2.0955)
			(size 0.7112 4.191)
			(layers "F.Cu" "F.Mask" "F.Paste")
			(net "GND")
		)
		(pad "A80" smd rect
			(at -69.499988 -2.0955)
			(size 0.7112 4.191)
			(layers "F.Cu" "F.Mask" "F.Paste")
			(net "GND")
		)
		(pad "A81" smd rect
			(at -70.499986 -2.0955)
			(size 0.7112 4.191)
			(layers "F.Cu" "F.Mask" "F.Paste")
			(net "P12V")
		)
		(pad "A82" smd rect
			(at -71.499984 -2.0955)
			(size 0.7112 4.191)
			(layers "F.Cu" "F.Mask" "F.Paste")
			(net "P12V")
		)
		(pad "B1" smd rect
			(at 11.500104 -1.7145)
			(size 0.7112 4.191)
			(drill
				(offset 0 -0.381)
			)
			(layers "F.Cu" "F.Mask" "F.Paste")
			(net "P12V")
		)
		(pad "B2" smd rect
			(at 10.500106 -1.7145)
			(size 0.7112 4.191)
			(drill
				(offset 0 -0.381)
			)
			(layers "F.Cu" "F.Mask" "F.Paste")
			(net "P12V")
		)
		(pad "B3" smd rect
			(at 9.500108 -1.7145)
			(size 0.7112 4.191)
			(drill
				(offset 0 -0.381)
			)
			(layers "F.Cu" "F.Mask" "F.Paste")
			(net "P12V")
		)
		(pad "B4" smd rect
			(at 8.50011 -1.7145)
			(size 0.7112 4.191)
			(drill
				(offset 0 -0.381)
			)
			(layers "F.Cu" "F.Mask" "F.Paste")
			(net "GND")
		)
		(pad "B5" smd rect
			(at 7.500112 -1.7145)
			(size 0.7112 4.191)
			(drill
				(offset 0 -0.381)
			)
			(layers "F.Cu" "F.Mask" "F.Paste")
			(net "BMC_I2C_CLK")
		)
		(pad "B6" smd rect
			(at 6.500114 -1.7145)
			(size 0.7112 4.191)
			(drill
				(offset 0 -0.381)
			)
			(layers "F.Cu" "F.Mask" "F.Paste")
			(net "BMC_I2C_DATA")
		)
		(pad "B7" smd rect
			(at 5.500116 -1.7145)
			(size 0.7112 4.191)
			(drill
				(offset 0 -0.381)
			)
			(layers "F.Cu" "F.Mask" "F.Paste")
			(net "GND")
		)
		(pad "B8" smd rect
			(at 4.500118 -1.7145)
			(size 0.7112 4.191)
			(drill
				(offset 0 -0.381)
			)
			(layers "F.Cu" "F.Mask" "F.Paste")
			(net "PMU_PWRBTN#")
		)
		(pad "B9" smd rect
			(at 3.50012 -1.7145)
			(size 0.7112 4.191)
			(drill
				(offset 0 -0.381)
			)
			(layers "F.Cu" "F.Mask" "F.Paste")
			(net "USB_P1_DP")
		)
		(pad "B10" smd rect
			(at 2.500122 -1.7145)
			(size 0.7112 4.191)
			(drill
				(offset 0 -0.381)
			)
			(layers "F.Cu" "F.Mask" "F.Paste")
			(net "USB_P1_DN")
		)
		(pad "B11" smd rect
			(at 1.500124 -1.7145)
			(size 0.7112 4.191)
			(drill
				(offset 0 -0.381)
			)
			(layers "F.Cu" "F.Mask" "F.Paste")
			(net "BMC_SYS_RESET#")
		)
		(pad "B12" smd rect
			(at -1.500124 -1.7145)
			(size 0.7112 4.191)
			(drill
				(offset 0 -0.381)
			)
			(layers "F.Cu" "F.Mask" "F.Paste")
			(net "BMC_I2C_ALERT#")
		)
		(pad "B13" smd rect
			(at -2.500122 -1.7145)
			(size 0.7112 4.191)
			(drill
				(offset 0 -0.381)
			)
			(layers "F.Cu" "F.Mask" "F.Paste")
			(net "GND")
		)
		(pad "B14" smd rect
			(at -3.50012 -1.7145)
			(size 0.7112 4.191)
			(drill
				(offset 0 -0.381)
			)
			(layers "F.Cu" "F.Mask" "F.Paste")
			(net "GND")
		)
		(pad "B15" smd rect
			(at -4.500118 -1.7145)
			(size 0.7112 4.191)
			(drill
				(offset 0 -0.381)
			)
			(layers "F.Cu" "F.Mask" "F.Paste")
			(net "P2E_CPU_SAS_TX_DP0")
		)
		(pad "B16" smd rect
			(at -5.500116 -1.7145)
			(size 0.7112 4.191)
			(drill
				(offset 0 -0.381)
			)
			(layers "F.Cu" "F.Mask" "F.Paste")
			(net "P2E_CPU_SAS_TX_DN0")
		)
		(pad "B17" smd rect
			(at -6.500114 -2.5908)
			(size 0.7112 3.2004)
			(layers "F.Cu" "F.Mask" "F.Paste")
			(net "GND")
		)
		(pad "B18" smd rect
			(at -7.500112 -1.7145)
			(size 0.7112 4.191)
			(drill
				(offset 0 -0.381)
			)
			(layers "F.Cu" "F.Mask" "F.Paste")
			(net "GND")
		)
		(pad "B19" smd rect
			(at -8.50011 -1.7145)
			(size 0.7112 4.191)
			(drill
				(offset 0 -0.381)
			)
			(layers "F.Cu" "F.Mask" "F.Paste")
			(net "P2E_CPU_SAS_TX_DP1")
		)
		(pad "B20" smd rect
			(at -9.500108 -1.7145)
			(size 0.7112 4.191)
			(drill
				(offset 0 -0.381)
			)
			(layers "F.Cu" "F.Mask" "F.Paste")
			(net "P2E_CPU_SAS_TX_DN1")
		)
		(pad "B21" smd rect
			(at -10.500106 -1.7145)
			(size 0.7112 4.191)
			(drill
				(offset 0 -0.381)
			)
			(layers "F.Cu" "F.Mask" "F.Paste")
			(net "GND")
		)
		(pad "B22" smd rect
			(at -11.500104 -1.7145)
			(size 0.7112 4.191)
			(drill
				(offset 0 -0.381)
			)
			(layers "F.Cu" "F.Mask" "F.Paste")
			(net "GND")
		)
		(pad "B23" smd rect
			(at -12.500102 -1.7145)
			(size 0.7112 4.191)
			(drill
				(offset 0 -0.381)
			)
			(layers "F.Cu" "F.Mask" "F.Paste")
			(net "P2E_CPU_SAS_TX_DP2")
		)
		(pad "B24" smd rect
			(at -13.5001 -1.7145)
			(size 0.7112 4.191)
			(drill
				(offset 0 -0.381)
			)
			(layers "F.Cu" "F.Mask" "F.Paste")
			(net "P2E_CPU_SAS_TX_DN2")
		)
		(pad "B25" smd rect
			(at -14.500098 -1.7145)
			(size 0.7112 4.191)
			(drill
				(offset 0 -0.381)
			)
			(layers "F.Cu" "F.Mask" "F.Paste")
			(net "GND")
		)
		(pad "B26" smd rect
			(at -15.500096 -1.7145)
			(size 0.7112 4.191)
			(drill
				(offset 0 -0.381)
			)
			(layers "F.Cu" "F.Mask" "F.Paste")
			(net "GND")
		)
		(pad "B27" smd rect
			(at -16.500094 -1.7145)
			(size 0.7112 4.191)
			(drill
				(offset 0 -0.381)
			)
			(layers "F.Cu" "F.Mask" "F.Paste")
			(net "P2E_CPU_SAS_TX_DP3")
		)
		(pad "B28" smd rect
			(at -17.500092 -1.7145)
			(size 0.7112 4.191)
			(drill
				(offset 0 -0.381)
			)
			(layers "F.Cu" "F.Mask" "F.Paste")
			(net "P2E_CPU_SAS_TX_DN3")
		)
		(pad "B29" smd rect
			(at -18.50009 -1.7145)
			(size 0.7112 4.191)
			(drill
				(offset 0 -0.381)
			)
			(layers "F.Cu" "F.Mask" "F.Paste")
			(net "GND")
		)
		(pad "B30" smd rect
			(at -19.500088 -1.7145)
			(size 0.7112 4.191)
			(drill
				(offset 0 -0.381)
			)
			(layers "F.Cu" "F.Mask" "F.Paste")
			(net "GND")
		)
		(pad "B31" smd rect
			(at -20.500086 -2.5908)
			(size 0.7112 3.2004)
			(layers "F.Cu" "F.Mask" "F.Paste")
			(net "SATA2_TX_C_DP0")
		)
		(pad "B32" smd rect
			(at -21.500084 -1.7145)
			(size 0.7112 4.191)
			(drill
				(offset 0 -0.381)
			)
			(layers "F.Cu" "F.Mask" "F.Paste")
			(net "SATA2_TX_C_DN0")
		)
		(pad "B33" smd rect
			(at -22.500082 -1.7145)
			(size 0.7112 4.191)
			(drill
				(offset 0 -0.381)
			)
			(layers "F.Cu" "F.Mask" "F.Paste")
			(net "GND")
		)
		(pad "B34" smd rect
			(at -23.50008 -1.7145)
			(size 0.7112 4.191)
			(drill
				(offset 0 -0.381)
			)
			(layers "F.Cu" "F.Mask" "F.Paste")
			(net "GND")
		)
		(pad "B35" smd rect
			(at -24.500078 -1.7145)
			(size 0.7112 4.191)
			(drill
				(offset 0 -0.381)
			)
			(layers "F.Cu" "F.Mask" "F.Paste")
			(net "CLK_100M_CLKBUFF_ENET_DP")
		)
		(pad "B36" smd rect
			(at -25.500076 -1.7145)
			(size 0.7112 4.191)
			(drill
				(offset 0 -0.381)
			)
			(layers "F.Cu" "F.Mask" "F.Paste")
			(net "CLK_100M_CLKBUFF_ENET_DN")
		)
		(pad "B37" smd rect
			(at -26.500074 -1.7145)
			(size 0.7112 4.191)
			(drill
				(offset 0 -0.381)
			)
			(layers "F.Cu" "F.Mask" "F.Paste")
			(net "GND")
		)
		(pad "B38" smd rect
			(at -27.500072 -1.7145)
			(size 0.7112 4.191)
			(drill
				(offset 0 -0.381)
			)
			(layers "F.Cu" "F.Mask" "F.Paste")
			(net "GND")
		)
		(pad "B39" smd rect
			(at -28.50007 -1.7145)
			(size 0.7112 4.191)
			(drill
				(offset 0 -0.381)
			)
			(layers "F.Cu" "F.Mask" "F.Paste")
			(net "PCIE1_RESET#")
		)
		(pad "B40" smd rect
			(at -29.500068 -1.7145)
			(size 0.7112 4.191)
			(drill
				(offset 0 -0.381)
			)
			(layers "F.Cu" "F.Mask" "F.Paste")
			(net "PCIE_RSVD_B40")
		)
		(pad "B41" smd rect
			(at -30.500066 -1.7145)
			(size 0.7112 4.191)
			(drill
				(offset 0 -0.381)
			)
			(layers "F.Cu" "F.Mask" "F.Paste")
			(net "GND")
		)
		(pad "B42" smd rect
			(at -31.500064 -1.7145)
			(size 0.7112 4.191)
			(drill
				(offset 0 -0.381)
			)
			(layers "F.Cu" "F.Mask" "F.Paste")
			(net "GND")
		)
		(pad "B43" smd rect
			(at -32.500062 -1.7145)
			(size 0.7112 4.191)
			(drill
				(offset 0 -0.381)
			)
			(layers "F.Cu" "F.Mask" "F.Paste")
			(net "GBE_SMBCLK_R")
		)
		(pad "B44" smd rect
			(at -33.50006 -1.7145)
			(size 0.7112 4.191)
			(drill
				(offset 0 -0.381)
			)
			(layers "F.Cu" "F.Mask" "F.Paste")
			(net "GBE_SMDATA_R")
		)
		(pad "B45" smd rect
			(at -34.500058 -1.7145)
			(size 0.7112 4.191)
			(drill
				(offset 0 -0.381)
			)
			(layers "F.Cu" "F.Mask" "F.Paste")
			(net "GND")
		)
		(pad "B46" smd rect
			(at -35.500056 -1.7145)
			(size 0.7112 4.191)
			(drill
				(offset 0 -0.381)
			)
			(layers "F.Cu" "F.Mask" "F.Paste")
			(net "GND")
		)
		(pad "B47" smd rect
			(at -36.500054 -1.7145)
			(size 0.7112 4.191)
			(drill
				(offset 0 -0.381)
			)
			(layers "F.Cu" "F.Mask" "F.Paste")
			(net "CPU_GBE_TX_C_DP0")
		)
		(pad "B48" smd rect
			(at -37.500052 -2.5908)
			(size 0.7112 3.2004)
			(layers "F.Cu" "F.Mask" "F.Paste")
			(net "CPU_GBE_TX_C_DN0")
		)
		(pad "B49" smd rect
			(at -38.50005 -1.7145)
			(size 0.7112 4.191)
			(drill
				(offset 0 -0.381)
			)
			(layers "F.Cu" "F.Mask" "F.Paste")
			(net "GND")
		)
		(pad "B50" smd rect
			(at -39.500048 -1.7145)
			(size 0.7112 4.191)
			(drill
				(offset 0 -0.381)
			)
			(layers "F.Cu" "F.Mask" "F.Paste")
			(net "GND")
		)
		(pad "B51" smd rect
			(at -40.500046 -1.7145)
			(size 0.7112 4.191)
			(drill
				(offset 0 -0.381)
			)
			(layers "F.Cu" "F.Mask" "F.Paste")
			(net "P2E_CPU_SAS_TX_DP4")
		)
		(pad "B52" smd rect
			(at -41.500044 -1.7145)
			(size 0.7112 4.191)
			(drill
				(offset 0 -0.381)
			)
			(layers "F.Cu" "F.Mask" "F.Paste")
			(net "P2E_CPU_SAS_TX_DN4")
		)
		(pad "B53" smd rect
			(at -42.500042 -1.7145)
			(size 0.7112 4.191)
			(drill
				(offset 0 -0.381)
			)
			(layers "F.Cu" "F.Mask" "F.Paste")
			(net "GND")
		)
		(pad "B54" smd rect
			(at -43.50004 -1.7145)
			(size 0.7112 4.191)
			(drill
				(offset 0 -0.381)
			)
			(layers "F.Cu" "F.Mask" "F.Paste")
			(net "GND")
		)
		(pad "B55" smd rect
			(at -44.500038 -1.7145)
			(size 0.7112 4.191)
			(drill
				(offset 0 -0.381)
			)
			(layers "F.Cu" "F.Mask" "F.Paste")
			(net "P2E_CPU_SAS_TX_DP5")
		)
		(pad "B56" smd rect
			(at -45.500036 -1.7145)
			(size 0.7112 4.191)
			(drill
				(offset 0 -0.381)
			)
			(layers "F.Cu" "F.Mask" "F.Paste")
			(net "P2E_CPU_SAS_TX_DN5")
		)
		(pad "B57" smd rect
			(at -46.500034 -1.7145)
			(size 0.7112 4.191)
			(drill
				(offset 0 -0.381)
			)
			(layers "F.Cu" "F.Mask" "F.Paste")
			(net "GND")
		)
		(pad "B58" smd rect
			(at -47.500032 -1.7145)
			(size 0.7112 4.191)
			(drill
				(offset 0 -0.381)
			)
			(layers "F.Cu" "F.Mask" "F.Paste")
			(net "GND")
		)
		(pad "B59" smd rect
			(at -48.50003 -1.7145)
			(size 0.7112 4.191)
			(drill
				(offset 0 -0.381)
			)
			(layers "F.Cu" "F.Mask" "F.Paste")
			(net "P2E_CPU_SAS_TX_DP6")
		)
		(pad "B60" smd rect
			(at -49.500028 -1.7145)
			(size 0.7112 4.191)
			(drill
				(offset 0 -0.381)
			)
			(layers "F.Cu" "F.Mask" "F.Paste")
			(net "P2E_CPU_SAS_TX_DN6")
		)
		(pad "B61" smd rect
			(at -50.500026 -1.7145)
			(size 0.7112 4.191)
			(drill
				(offset 0 -0.381)
			)
			(layers "F.Cu" "F.Mask" "F.Paste")
			(net "GND")
		)
		(pad "B62" smd rect
			(at -51.500024 -1.7145)
			(size 0.7112 4.191)
			(drill
				(offset 0 -0.381)
			)
			(layers "F.Cu" "F.Mask" "F.Paste")
			(net "GND")
		)
		(pad "B63" smd rect
			(at -52.500022 -1.7145)
			(size 0.7112 4.191)
			(drill
				(offset 0 -0.381)
			)
			(layers "F.Cu" "F.Mask" "F.Paste")
			(net "P2E_CPU_SAS_TX_DP7")
		)
		(pad "B64" smd rect
			(at -53.50002 -1.7145)
			(size 0.7112 4.191)
			(drill
				(offset 0 -0.381)
			)
			(layers "F.Cu" "F.Mask" "F.Paste")
			(net "P2E_CPU_SAS_TX_DN7")
		)
		(pad "B65" smd rect
			(at -54.500018 -1.7145)
			(size 0.7112 4.191)
			(drill
				(offset 0 -0.381)
			)
			(layers "F.Cu" "F.Mask" "F.Paste")
			(net "GND")
		)
		(pad "B66" smd rect
			(at -55.500016 -1.7145)
			(size 0.7112 4.191)
			(drill
				(offset 0 -0.381)
			)
			(layers "F.Cu" "F.Mask" "F.Paste")
			(net "GND")
		)
		(pad "B67" smd rect
			(at -56.500014 -1.7145)
			(size 0.7112 4.191)
			(drill
				(offset 0 -0.381)
			)
			(layers "F.Cu" "F.Mask" "F.Paste")
			(net "P2E_CPU_ETH10G_TX_DP8")
		)
		(pad "B68" smd rect
			(at -57.500012 -1.7145)
			(size 0.7112 4.191)
			(drill
				(offset 0 -0.381)
			)
			(layers "F.Cu" "F.Mask" "F.Paste")
			(net "P2E_CPU_ETH10G_TX_DN8")
		)
		(pad "B69" smd rect
			(at -58.50001 -1.7145)
			(size 0.7112 4.191)
			(drill
				(offset 0 -0.381)
			)
			(layers "F.Cu" "F.Mask" "F.Paste")
			(net "GND")
		)
		(pad "B70" smd rect
			(at -59.500008 -1.7145)
			(size 0.7112 4.191)
			(drill
				(offset 0 -0.381)
			)
			(layers "F.Cu" "F.Mask" "F.Paste")
			(net "GND")
		)
		(pad "B71" smd rect
			(at -60.500006 -1.7145)
			(size 0.7112 4.191)
			(drill
				(offset 0 -0.381)
			)
			(layers "F.Cu" "F.Mask" "F.Paste")
			(net "P2E_CPU_ETH10G_TX_DP9")
		)
		(pad "B72" smd rect
			(at -61.500004 -1.7145)
			(size 0.7112 4.191)
			(drill
				(offset 0 -0.381)
			)
			(layers "F.Cu" "F.Mask" "F.Paste")
			(net "P2E_CPU_ETH10G_TX_DN9")
		)
		(pad "B73" smd rect
			(at -62.500002 -1.7145)
			(size 0.7112 4.191)
			(drill
				(offset 0 -0.381)
			)
			(layers "F.Cu" "F.Mask" "F.Paste")
			(net "GND")
		)
		(pad "B74" smd rect
			(at -63.5 -1.7145)
			(size 0.7112 4.191)
			(drill
				(offset 0 -0.381)
			)
			(layers "F.Cu" "F.Mask" "F.Paste")
			(net "GND")
		)
		(pad "B75" smd rect
			(at -64.499998 -1.7145)
			(size 0.7112 4.191)
			(drill
				(offset 0 -0.381)
			)
			(layers "F.Cu" "F.Mask" "F.Paste")
			(net "P2E_CPU_ETH10G_TX_DP10")
		)
		(pad "B76" smd rect
			(at -65.499996 -1.7145)
			(size 0.7112 4.191)
			(drill
				(offset 0 -0.381)
			)
			(layers "F.Cu" "F.Mask" "F.Paste")
			(net "P2E_CPU_ETH10G_TX_DN10")
		)
		(pad "B77" smd rect
			(at -66.499994 -1.7145)
			(size 0.7112 4.191)
			(drill
				(offset 0 -0.381)
			)
			(layers "F.Cu" "F.Mask" "F.Paste")
			(net "GND")
		)
		(pad "B78" smd rect
			(at -67.499992 -1.7145)
			(size 0.7112 4.191)
			(drill
				(offset 0 -0.381)
			)
			(layers "F.Cu" "F.Mask" "F.Paste")
			(net "GND")
		)
		(pad "B79" smd rect
			(at -68.49999 -1.7145)
			(size 0.7112 4.191)
			(drill
				(offset 0 -0.381)
			)
			(layers "F.Cu" "F.Mask" "F.Paste")
			(net "P2E_CPU_ETH10G_TX_DP11")
		)
		(pad "B80" smd rect
			(at -69.499988 -1.7145)
			(size 0.7112 4.191)
			(drill
				(offset 0 -0.381)
			)
			(layers "F.Cu" "F.Mask" "F.Paste")
			(net "P2E_CPU_ETH10G_TX_DN11")
		)
		(pad "B81" smd rect
			(at -70.499986 -2.5908)
			(size 0.7112 3.2004)
			(layers "F.Cu" "F.Mask" "F.Paste")
			(net "GND")
		)
		(pad "B82" smd rect
			(at -71.499984 -1.7145)
			(size 0.7112 4.191)
			(drill
				(offset 0 -0.381)
			)
			(layers "F.Cu" "F.Mask" "F.Paste")
			(net "GND")
		)
		(zone
			(layer "F.Cu")
			(hatch none 0.5)
			(connect_pads
				(clearance 0)
			)
			(min_thickness 0.25)
			(keepout
				(tracks allowed)
				(vias not_allowed)
				(pads allowed)
				(copperpour not_allowed)
				(footprints allowed)
			)
			(placement
				(enabled no)
				(sheetname "")
			)
			(fill
				(thermal_gap 0.5)
				(thermal_bridge_width 0.5)
				(island_removal_mode 0)
			)
			(polygon
				(pts
					(xy 4.627372 -0.384048) (xy 90.377772 -0.384048) (xy 90.377772 -6.607048) (xy 4.627372 -6.607048)
				)
			)
		)
		(zone
			(layer "F.Cu")
			(hatch none 0.5)
			(connect_pads
				(clearance 0)
			)
			(min_thickness 0.25)
			(keepout
				(tracks not_allowed)
				(vias allowed)
				(pads allowed)
				(copperpour not_allowed)
				(footprints allowed)
			)
			(placement
				(enabled no)
				(sheetname "")
			)
			(fill
				(thermal_gap 0.5)
				(thermal_bridge_width 0.5)
				(island_removal_mode 0)
			)
			(polygon
				(pts
					(xy 4.627372 -0.384048) (xy 90.377772 -0.384048) (xy 90.377772 -1.400048) (xy 4.627372 -1.400048)
				)
			)
		)
		(zone
			(layer "B.Cu")
			(hatch none 0.5)
			(connect_pads
				(clearance 0)
			)
			(min_thickness 0.25)
			(keepout
				(tracks allowed)
				(vias not_allowed)
				(pads allowed)
				(copperpour not_allowed)
				(footprints allowed)
			)
			(placement
				(enabled no)
				(sheetname "")
			)
			(fill
				(thermal_gap 0.5)
				(thermal_bridge_width 0.5)
				(island_removal_mode 0)
			)
			(polygon
				(pts
					(xy 4.627372 -0.384048) (xy 90.377772 -0.384048) (xy 90.377772 -6.607048) (xy 4.627372 -6.607048)
				)
			)
		)
		(zone
			(layer "B.Cu")
			(hatch none 0.5)
			(connect_pads
				(clearance 0)
			)
			(min_thickness 0.25)
			(keepout
				(tracks not_allowed)
				(vias allowed)
				(pads allowed)
				(copperpour not_allowed)
				(footprints allowed)
			)
			(placement
				(enabled no)
				(sheetname "")
			)
			(fill
				(thermal_gap 0.5)
				(thermal_bridge_width 0.5)
				(island_removal_mode 0)
			)
			(polygon
				(pts
					(xy 4.627372 -0.384048) (xy 90.377772 -0.384048) (xy 90.377772 -1.400048) (xy 4.627372 -1.400048)
				)
			)
		)
	)
	(footprint ""
		(layer "F.Cu")
		(at 77.350112 -19.899884 180)
		(property "Reference" "CN1"
			(at 0 0 180)
			(layer "F.SilkS")
			(hide yes)
			(effects
				(font
					(size 1.27 1.27)
				)
			)
		)
		(property "Value" "PCISLT164-44-GP"
			(at -23.3172 -6.8961 180)
			(unlocked yes)
			(layer "F.Fab")
			(hide yes)
			(effects
				(font
					(size 1.016 1.016)
					(thickness 0.1524)
				)
			)
		)
		(property "Device Type" "AAA-PCI-066-K06"
			(at -23.3172 -8.4201 180)
			(unlocked yes)
			(layer "F.Fab")
			(hide yes)
			(effects
				(font
					(size 1.016 1.016)
					(thickness 0.1524)
				)
			)
		)
		(duplicate_pad_numbers_are_jumpers no)
		(fp_line
			(start 74.5998 5.3594)
			(end -14.9098 5.3594)
			(stroke
				(width 0.1524)
				(type default)
			)
			(layer "F.SilkS")
		)
		(fp_line
			(start 74.5998 -4.0386)
			(end 74.5998 5.3594)
			(stroke
				(width 0.1524)
				(type default)
			)
			(layer "F.SilkS")
		)
		(fp_line
			(start -14.9098 5.3594)
			(end -14.9098 -4.0386)
			(stroke
				(width 0.1524)
				(type default)
			)
			(layer "F.SilkS")
		)
		(fp_line
			(start -14.9098 -4.0386)
			(end 74.5998 -4.0386)
			(stroke
				(width 0.1524)
				(type default)
			)
			(layer "F.SilkS")
		)
		(fp_rect
			(start -14.6558 5.1054)
			(end 74.3458 -3.683)
			(stroke
				(width 0)
				(type default)
			)
			(fill no)
			(layer "F.CrtYd")
		)
		(fp_poly
			(pts
				(xy -15.1638 5.6134) (xy -15.1638 0.00254) (xy -14.6558 0.00254) (xy -14.6558 5.1054) (xy 74.3458 5.1054)
				(xy 74.3458 -3.683) (xy -14.6558 -3.683) (xy -14.6558 -0.00254) (xy -15.1638 -0.00254) (xy -15.1638 -4.2926)
				(xy 74.8538 -4.2926) (xy 74.8538 5.6134)
			)
			(stroke
				(width 0)
				(type default)
			)
			(fill no)
			(layer "F.CrtYd")
		)
		(fp_rect
			(start -15.1638 5.6134)
			(end 74.8538 -4.2926)
			(stroke
				(width 0)
				(type default)
			)
			(fill no)
			(layer "F.Fab")
		)
		(pad "" np_thru_hole circle
			(at 0 0 180)
			(size 0.254 0.254)
			(drill 2.3622)
			(layers "*.Cu" "*.Mask")
			(clearance 1.4097)
			(thermal_gap 1.4097)
		)
		(pad "" np_thru_hole circle
			(at 73.14946 0 180)
			(size 0.254 0.254)
			(drill 2.3622)
			(layers "*.Cu" "*.Mask")
			(clearance 1.4097)
			(thermal_gap 1.4097)
		)
		(pad "A1" thru_hole circle
			(at -11.64971 -1.24968 180)
			(size 1.0922 1.0922)
			(drill 0.7366)
			(layers "*.Cu" "*.Mask")
			(remove_unused_layers no)
			(net "BOARD_PRSNT#")
			(clearance 0.1778)
			(thermal_gap 0.1778)
		)
		(pad "A2" thru_hole circle
			(at -10.65022 -3.24993 180)
			(size 1.0922 1.0922)
			(drill 0.7366)
			(layers "*.Cu" "*.Mask")
			(remove_unused_layers no)
			(net "P12V")
			(clearance 0.1778)
			(thermal_gap 0.1778)
		)
		(pad "A3" thru_hole circle
			(at -9.64946 -1.24968 180)
			(size 1.0922 1.0922)
			(drill 0.7366)
			(layers "*.Cu" "*.Mask")
			(remove_unused_layers no)
			(net "P12V")
			(clearance 0.1778)
			(thermal_gap 0.1778)
		)
		(pad "A4" thru_hole circle
			(at -8.64997 -3.24993 180)
			(size 1.0922 1.0922)
			(drill 0.7366)
			(layers "*.Cu" "*.Mask")
			(remove_unused_layers no)
			(net "GND")
			(clearance 0.1778)
			(thermal_gap 0.1778)
		)
		(pad "A5" thru_hole circle
			(at -7.65048 -1.24968 180)
			(size 1.0922 1.0922)
			(drill 0.7366)
			(layers "*.Cu" "*.Mask")
			(remove_unused_layers no)
			(net "SLOT_ID0")
			(clearance 0.1778)
			(thermal_gap 0.1778)
		)
		(pad "A6" thru_hole circle
			(at -6.64972 -3.24993 180)
			(size 1.0922 1.0922)
			(drill 0.7366)
			(layers "*.Cu" "*.Mask")
			(remove_unused_layers no)
			(net "SLOT_ID1")
			(clearance 0.1778)
			(thermal_gap 0.1778)
		)
		(pad "A7" thru_hole circle
			(at -5.65023 -1.24968 180)
			(size 1.0922 1.0922)
			(drill 0.7366)
			(layers "*.Cu" "*.Mask")
			(remove_unused_layers no)
			(net "CPU_TXD")
			(clearance 0.1778)
			(thermal_gap 0.1778)
		)
		(pad "A8" thru_hole circle
			(at -4.64947 -3.24993 180)
			(size 1.0922 1.0922)
			(drill 0.7366)
			(layers "*.Cu" "*.Mask")
			(remove_unused_layers no)
			(net "CPU_RXD")
			(clearance 0.1778)
			(thermal_gap 0.1778)
		)
		(pad "A9" thru_hole circle
			(at -3.64998 -1.24968 180)
			(size 1.0922 1.0922)
			(drill 0.7366)
			(layers "*.Cu" "*.Mask")
			(remove_unused_layers no)
			(net "SLOT_ID2")
			(clearance 0.1778)
			(thermal_gap 0.1778)
		)
		(pad "A10" thru_hole circle
			(at -2.65049 -3.24993 180)
			(size 1.0922 1.0922)
			(drill 0.7366)
			(layers "*.Cu" "*.Mask")
			(remove_unused_layers no)
			(net "SLOT_ID3")
			(clearance 0.1778)
			(thermal_gap 0.1778)
		)
		(pad "A11" thru_hole circle
			(at -1.64973 -1.24968 180)
			(size 1.0922 1.0922)
			(drill 0.7366)
			(layers "*.Cu" "*.Mask")
			(remove_unused_layers no)
			(net "PCIE_RESET#")
			(clearance 0.1778)
			(thermal_gap 0.1778)
		)
		(pad "A12" thru_hole circle
			(at 1.35001 -3.24993 180)
			(size 1.0922 1.0922)
			(drill 0.7366)
			(layers "*.Cu" "*.Mask")
			(remove_unused_layers no)
			(net "GND")
			(clearance 0.1778)
			(thermal_gap 0.1778)
		)
		(pad "A13" thru_hole circle
			(at 2.3495 -1.24968 180)
			(size 1.0922 1.0922)
			(drill 0.7366)
			(layers "*.Cu" "*.Mask")
			(remove_unused_layers no)
			(net "CLK_100M_PCIE_SAS_C_P")
			(clearance 0.1778)
			(thermal_gap 0.1778)
		)
		(pad "A14" thru_hole circle
			(at 3.35026 -3.24993 180)
			(size 1.0922 1.0922)
			(drill 0.7366)
			(layers "*.Cu" "*.Mask")
			(remove_unused_layers no)
			(net "CLK_100M_PCIE_SAS_C_N")
			(clearance 0.1778)
			(thermal_gap 0.1778)
		)
		(pad "A15" thru_hole circle
			(at 4.34975 -1.24968 180)
			(size 1.0922 1.0922)
			(drill 0.7366)
			(layers "*.Cu" "*.Mask")
			(remove_unused_layers no)
			(net "GND")
			(clearance 0.1778)
			(thermal_gap 0.1778)
		)
		(pad "A16" thru_hole circle
			(at 5.35051 -3.24993 180)
			(size 1.0922 1.0922)
			(drill 0.7366)
			(layers "*.Cu" "*.Mask")
			(remove_unused_layers no)
			(net "GND")
			(clearance 0.1778)
			(thermal_gap 0.1778)
		)
		(pad "A17" thru_hole circle
			(at 6.35 -1.24968 180)
			(size 1.0922 1.0922)
			(drill 0.7366)
			(layers "*.Cu" "*.Mask")
			(remove_unused_layers no)
			(net "P2E_CPU_SAS_RX_DP0")
			(clearance 0.1778)
			(thermal_gap 0.1778)
		)
		(pad "A18" thru_hole circle
			(at 7.34949 -3.24993 180)
			(size 1.0922 1.0922)
			(drill 0.7366)
			(layers "*.Cu" "*.Mask")
			(remove_unused_layers no)
			(net "P2E_CPU_SAS_RX_DN0")
			(clearance 0.1778)
			(thermal_gap 0.1778)
		)
		(pad "A19" thru_hole circle
			(at 8.35025 -1.24968 180)
			(size 1.0922 1.0922)
			(drill 0.7366)
			(layers "*.Cu" "*.Mask")
			(remove_unused_layers no)
			(net "GND")
			(clearance 0.1778)
			(thermal_gap 0.1778)
		)
		(pad "A20" thru_hole circle
			(at 9.34974 -3.24993 180)
			(size 1.0922 1.0922)
			(drill 0.7366)
			(layers "*.Cu" "*.Mask")
			(remove_unused_layers no)
			(net "GND")
			(clearance 0.1778)
			(thermal_gap 0.1778)
		)
		(pad "A21" thru_hole circle
			(at 10.3505 -1.24968 180)
			(size 1.0922 1.0922)
			(drill 0.7366)
			(layers "*.Cu" "*.Mask")
			(remove_unused_layers no)
			(net "P2E_CPU_SAS_RX_DP1")
			(clearance 0.1778)
			(thermal_gap 0.1778)
		)
		(pad "A22" thru_hole circle
			(at 11.34999 -3.24993 180)
			(size 1.0922 1.0922)
			(drill 0.7366)
			(layers "*.Cu" "*.Mask")
			(remove_unused_layers no)
			(net "P2E_CPU_SAS_RX_DN1")
			(clearance 0.1778)
			(thermal_gap 0.1778)
		)
		(pad "A23" thru_hole circle
			(at 12.34948 -1.24968 180)
			(size 1.0922 1.0922)
			(drill 0.7366)
			(layers "*.Cu" "*.Mask")
			(remove_unused_layers no)
			(net "GND")
			(clearance 0.1778)
			(thermal_gap 0.1778)
		)
		(pad "A24" thru_hole circle
			(at 13.35024 -3.24993 180)
			(size 1.0922 1.0922)
			(drill 0.7366)
			(layers "*.Cu" "*.Mask")
			(remove_unused_layers no)
			(net "GND")
			(clearance 0.1778)
			(thermal_gap 0.1778)
		)
		(pad "A25" thru_hole circle
			(at 14.34973 -1.24968 180)
			(size 1.0922 1.0922)
			(drill 0.7366)
			(layers "*.Cu" "*.Mask")
			(remove_unused_layers no)
			(net "P2E_CPU_SAS_RX_DP2")
			(clearance 0.1778)
			(thermal_gap 0.1778)
		)
		(pad "A26" thru_hole circle
			(at 15.35049 -3.24993 180)
			(size 1.0922 1.0922)
			(drill 0.7366)
			(layers "*.Cu" "*.Mask")
			(remove_unused_layers no)
			(net "P2E_CPU_SAS_RX_DN2")
			(clearance 0.1778)
			(thermal_gap 0.1778)
		)
		(pad "A27" thru_hole circle
			(at 16.34998 -1.24968 180)
			(size 1.0922 1.0922)
			(drill 0.7366)
			(layers "*.Cu" "*.Mask")
			(remove_unused_layers no)
			(net "GND")
			(clearance 0.1778)
			(thermal_gap 0.1778)
		)
		(pad "A28" thru_hole circle
			(at 17.34947 -3.24993 180)
			(size 1.0922 1.0922)
			(drill 0.7366)
			(layers "*.Cu" "*.Mask")
			(remove_unused_layers no)
			(net "GND")
			(clearance 0.1778)
			(thermal_gap 0.1778)
		)
		(pad "A29" thru_hole circle
			(at 18.35023 -1.24968 180)
			(size 1.0922 1.0922)
			(drill 0.7366)
			(layers "*.Cu" "*.Mask")
			(remove_unused_layers no)
			(net "P2E_CPU_SAS_RX_DP3")
			(clearance 0.1778)
			(thermal_gap 0.1778)
		)
		(pad "A30" thru_hole circle
			(at 19.34972 -3.24993 180)
			(size 1.0922 1.0922)
			(drill 0.7366)
			(layers "*.Cu" "*.Mask")
			(remove_unused_layers no)
			(net "P2E_CPU_SAS_RX_DN3")
			(clearance 0.1778)
			(thermal_gap 0.1778)
		)
		(pad "A31" thru_hole circle
			(at 20.35048 -1.24968 180)
			(size 1.0922 1.0922)
			(drill 0.7366)
			(layers "*.Cu" "*.Mask")
			(remove_unused_layers no)
			(net "GND")
			(clearance 0.1778)
			(thermal_gap 0.1778)
		)
		(pad "A32" thru_hole circle
			(at 21.34997 -3.24993 180)
			(size 1.0922 1.0922)
			(drill 0.7366)
			(layers "*.Cu" "*.Mask")
			(remove_unused_layers no)
			(net "GND")
			(clearance 0.1778)
			(thermal_gap 0.1778)
		)
		(pad "A33" thru_hole circle
			(at 22.34946 -1.24968 180)
			(size 1.0922 1.0922)
			(drill 0.7366)
			(layers "*.Cu" "*.Mask")
			(remove_unused_layers no)
			(net "SATA2_RX_C_DP0")
			(clearance 0.1778)
			(thermal_gap 0.1778)
		)
		(pad "A34" thru_hole circle
			(at 23.35022 -3.24993 180)
			(size 1.0922 1.0922)
			(drill 0.7366)
			(layers "*.Cu" "*.Mask")
			(remove_unused_layers no)
			(net "SATA2_RX_C_DN0")
			(clearance 0.1778)
			(thermal_gap 0.1778)
		)
		(pad "A35" thru_hole circle
			(at 24.34971 -1.24968 180)
			(size 1.0922 1.0922)
			(drill 0.7366)
			(layers "*.Cu" "*.Mask")
			(remove_unused_layers no)
			(net "GND")
			(clearance 0.1778)
			(thermal_gap 0.1778)
		)
		(pad "A36" thru_hole circle
			(at 25.35047 -3.24993 180)
			(size 1.0922 1.0922)
			(drill 0.7366)
			(layers "*.Cu" "*.Mask")
			(remove_unused_layers no)
			(net "GND")
			(clearance 0.1778)
			(thermal_gap 0.1778)
		)
		(pad "A37" thru_hole circle
			(at 26.34996 -1.24968 180)
			(size 1.0922 1.0922)
			(drill 0.7366)
			(layers "*.Cu" "*.Mask")
			(remove_unused_layers no)
			(net "PCIE_RSVD_A37")
			(clearance 0.1778)
			(thermal_gap 0.1778)
		)
		(pad "A38" thru_hole circle
			(at 27.34945 -3.24993 180)
			(size 1.0922 1.0922)
			(drill 0.7366)
			(layers "*.Cu" "*.Mask")
			(remove_unused_layers no)
			(net "PCIE_RSVD_A38")
			(clearance 0.1778)
			(thermal_gap 0.1778)
		)
		(pad "A39" thru_hole circle
			(at 28.35021 -1.24968 180)
			(size 1.0922 1.0922)
			(drill 0.7366)
			(layers "*.Cu" "*.Mask")
			(remove_unused_layers no)
			(net "GND")
			(clearance 0.1778)
			(thermal_gap 0.1778)
		)
		(pad "A40" thru_hole circle
			(at 29.3497 -3.24993 180)
			(size 1.0922 1.0922)
			(drill 0.7366)
			(layers "*.Cu" "*.Mask")
			(remove_unused_layers no)
			(net "GND")
			(clearance 0.1778)
			(thermal_gap 0.1778)
		)
		(pad "A41" thru_hole circle
			(at 30.35046 -1.24968 180)
			(size 1.0922 1.0922)
			(drill 0.7366)
			(layers "*.Cu" "*.Mask")
			(remove_unused_layers no)
			(net "PCIE_RSVD_A41")
			(clearance 0.1778)
			(thermal_gap 0.1778)
		)
		(pad "A42" thru_hole circle
			(at 31.34995 -3.24993 180)
			(size 1.0922 1.0922)
			(drill 0.7366)
			(layers "*.Cu" "*.Mask")
			(remove_unused_layers no)
			(net "GBE_SMBALRT_R#")
			(clearance 0.1778)
			(thermal_gap 0.1778)
		)
		(pad "A43" thru_hole circle
			(at 32.34944 -1.24968 180)
			(size 1.0922 1.0922)
			(drill 0.7366)
			(layers "*.Cu" "*.Mask")
			(remove_unused_layers no)
			(net "GND")
			(clearance 0.1778)
			(thermal_gap 0.1778)
		)
		(pad "A44" thru_hole circle
			(at 33.3502 -3.24993 180)
			(size 1.0922 1.0922)
			(drill 0.7366)
			(layers "*.Cu" "*.Mask")
			(remove_unused_layers no)
			(net "GND")
			(clearance 0.1778)
			(thermal_gap 0.1778)
		)
		(pad "A45" thru_hole circle
			(at 34.34969 -1.24968 180)
			(size 1.0922 1.0922)
			(drill 0.7366)
			(layers "*.Cu" "*.Mask")
			(remove_unused_layers no)
			(net "CPU_GBE_RX_C_DP0")
			(clearance 0.1778)
			(thermal_gap 0.1778)
		)
		(pad "A46" thru_hole circle
			(at 35.35045 -3.24993 180)
			(size 1.0922 1.0922)
			(drill 0.7366)
			(layers "*.Cu" "*.Mask")
			(remove_unused_layers no)
			(net "CPU_GBE_RX_C_DN0")
			(clearance 0.1778)
			(thermal_gap 0.1778)
		)
		(pad "A47" thru_hole circle
			(at 36.34994 -1.24968 180)
			(size 1.0922 1.0922)
			(drill 0.7366)
			(layers "*.Cu" "*.Mask")
			(remove_unused_layers no)
			(net "GND")
			(clearance 0.1778)
			(thermal_gap 0.1778)
		)
		(pad "A48" thru_hole circle
			(at 37.34943 -3.24993 180)
			(size 1.0922 1.0922)
			(drill 0.7366)
			(layers "*.Cu" "*.Mask")
			(remove_unused_layers no)
			(net "GND")
			(clearance 0.1778)
			(thermal_gap 0.1778)
		)
		(pad "A49" thru_hole circle
			(at 38.35019 -1.24968 180)
			(size 1.0922 1.0922)
			(drill 0.7366)
			(layers "*.Cu" "*.Mask")
			(remove_unused_layers no)
			(net "P2E_CPU_SAS_RX_DP4")
			(clearance 0.1778)
			(thermal_gap 0.1778)
		)
		(pad "A50" thru_hole circle
			(at 39.34968 -3.24993 180)
			(size 1.0922 1.0922)
			(drill 0.7366)
			(layers "*.Cu" "*.Mask")
			(remove_unused_layers no)
			(net "P2E_CPU_SAS_RX_DN4")
			(clearance 0.1778)
			(thermal_gap 0.1778)
		)
		(pad "A51" thru_hole circle
			(at 40.35044 -1.24968 180)
			(size 1.0922 1.0922)
			(drill 0.7366)
			(layers "*.Cu" "*.Mask")
			(remove_unused_layers no)
			(net "GND")
			(clearance 0.1778)
			(thermal_gap 0.1778)
		)
		(pad "A52" thru_hole circle
			(at 41.34993 -3.24993 180)
			(size 1.0922 1.0922)
			(drill 0.7366)
			(layers "*.Cu" "*.Mask")
			(remove_unused_layers no)
			(net "GND")
			(clearance 0.1778)
			(thermal_gap 0.1778)
		)
		(pad "A53" thru_hole circle
			(at 42.34942 -1.24968 180)
			(size 1.0922 1.0922)
			(drill 0.7366)
			(layers "*.Cu" "*.Mask")
			(remove_unused_layers no)
			(net "P2E_CPU_SAS_RX_DP5")
			(clearance 0.1778)
			(thermal_gap 0.1778)
		)
		(pad "A54" thru_hole circle
			(at 43.35018 -3.24993 180)
			(size 1.0922 1.0922)
			(drill 0.7366)
			(layers "*.Cu" "*.Mask")
			(remove_unused_layers no)
			(net "P2E_CPU_SAS_RX_DN5")
			(clearance 0.1778)
			(thermal_gap 0.1778)
		)
		(pad "A55" thru_hole circle
			(at 44.34967 -1.24968 180)
			(size 1.0922 1.0922)
			(drill 0.7366)
			(layers "*.Cu" "*.Mask")
			(remove_unused_layers no)
			(net "GND")
			(clearance 0.1778)
			(thermal_gap 0.1778)
		)
		(pad "A56" thru_hole circle
			(at 45.35043 -3.24993 180)
			(size 1.0922 1.0922)
			(drill 0.7366)
			(layers "*.Cu" "*.Mask")
			(remove_unused_layers no)
			(net "GND")
			(clearance 0.1778)
			(thermal_gap 0.1778)
		)
		(pad "A57" thru_hole circle
			(at 46.34992 -1.24968 180)
			(size 1.0922 1.0922)
			(drill 0.7366)
			(layers "*.Cu" "*.Mask")
			(remove_unused_layers no)
			(net "P2E_CPU_SAS_RX_DP6")
			(clearance 0.1778)
			(thermal_gap 0.1778)
		)
		(pad "A58" thru_hole circle
			(at 47.34941 -3.24993 180)
			(size 1.0922 1.0922)
			(drill 0.7366)
			(layers "*.Cu" "*.Mask")
			(remove_unused_layers no)
			(net "P2E_CPU_SAS_RX_DN6")
			(clearance 0.1778)
			(thermal_gap 0.1778)
		)
		(pad "A59" thru_hole circle
			(at 48.35017 -1.24968 180)
			(size 1.0922 1.0922)
			(drill 0.7366)
			(layers "*.Cu" "*.Mask")
			(remove_unused_layers no)
			(net "GND")
			(clearance 0.1778)
			(thermal_gap 0.1778)
		)
		(pad "A60" thru_hole circle
			(at 49.34966 -3.24993 180)
			(size 1.0922 1.0922)
			(drill 0.7366)
			(layers "*.Cu" "*.Mask")
			(remove_unused_layers no)
			(net "GND")
			(clearance 0.1778)
			(thermal_gap 0.1778)
		)
		(pad "A61" thru_hole circle
			(at 50.35042 -1.24968 180)
			(size 1.0922 1.0922)
			(drill 0.7366)
			(layers "*.Cu" "*.Mask")
			(remove_unused_layers no)
			(net "P2E_CPU_SAS_RX_DP7")
			(clearance 0.1778)
			(thermal_gap 0.1778)
		)
		(pad "A62" thru_hole circle
			(at 51.34991 -3.24993 180)
			(size 1.0922 1.0922)
			(drill 0.7366)
			(layers "*.Cu" "*.Mask")
			(remove_unused_layers no)
			(net "P2E_CPU_SAS_RX_DN7")
			(clearance 0.1778)
			(thermal_gap 0.1778)
		)
		(pad "A63" thru_hole circle
			(at 52.3494 -1.24968 180)
			(size 1.0922 1.0922)
			(drill 0.7366)
			(layers "*.Cu" "*.Mask")
			(remove_unused_layers no)
			(net "GND")
			(clearance 0.1778)
			(thermal_gap 0.1778)
		)
		(pad "A64" thru_hole circle
			(at 53.35016 -3.24993 180)
			(size 1.0922 1.0922)
			(drill 0.7366)
			(layers "*.Cu" "*.Mask")
			(remove_unused_layers no)
			(net "GND")
			(clearance 0.1778)
			(thermal_gap 0.1778)
		)
		(pad "A65" thru_hole circle
			(at 54.34965 -1.24968 180)
			(size 1.0922 1.0922)
			(drill 0.7366)
			(layers "*.Cu" "*.Mask")
			(remove_unused_layers no)
			(net "P2E_CPU_ETH10G_RX_DP8")
			(clearance 0.1778)
			(thermal_gap 0.1778)
		)
		(pad "A66" thru_hole circle
			(at 55.35041 -3.24993 180)
			(size 1.0922 1.0922)
			(drill 0.7366)
			(layers "*.Cu" "*.Mask")
			(remove_unused_layers no)
			(net "P2E_CPU_ETH10G_RX_DN8")
			(clearance 0.1778)
			(thermal_gap 0.1778)
		)
		(pad "A67" thru_hole circle
			(at 56.3499 -1.24968 180)
			(size 1.0922 1.0922)
			(drill 0.7366)
			(layers "*.Cu" "*.Mask")
			(remove_unused_layers no)
			(net "GND")
			(clearance 0.1778)
			(thermal_gap 0.1778)
		)
		(pad "A68" thru_hole circle
			(at 57.34939 -3.24993 180)
			(size 1.0922 1.0922)
			(drill 0.7366)
			(layers "*.Cu" "*.Mask")
			(remove_unused_layers no)
			(net "GND")
			(clearance 0.1778)
			(thermal_gap 0.1778)
		)
		(pad "A69" thru_hole circle
			(at 58.35015 -1.24968 180)
			(size 1.0922 1.0922)
			(drill 0.7366)
			(layers "*.Cu" "*.Mask")
			(remove_unused_layers no)
			(net "P2E_CPU_ETH10G_RX_DP9")
			(clearance 0.1778)
			(thermal_gap 0.1778)
		)
		(pad "A70" thru_hole circle
			(at 59.34964 -3.24993 180)
			(size 1.0922 1.0922)
			(drill 0.7366)
			(layers "*.Cu" "*.Mask")
			(remove_unused_layers no)
			(net "P2E_CPU_ETH10G_RX_DN9")
			(clearance 0.1778)
			(thermal_gap 0.1778)
		)
		(pad "A71" thru_hole circle
			(at 60.3504 -1.24968 180)
			(size 1.0922 1.0922)
			(drill 0.7366)
			(layers "*.Cu" "*.Mask")
			(remove_unused_layers no)
			(net "GND")
			(clearance 0.1778)
			(thermal_gap 0.1778)
		)
		(pad "A72" thru_hole circle
			(at 61.34989 -3.24993 180)
			(size 1.0922 1.0922)
			(drill 0.7366)
			(layers "*.Cu" "*.Mask")
			(remove_unused_layers no)
			(net "GND")
			(clearance 0.1778)
			(thermal_gap 0.1778)
		)
		(pad "A73" thru_hole circle
			(at 62.34938 -1.24968 180)
			(size 1.0922 1.0922)
			(drill 0.7366)
			(layers "*.Cu" "*.Mask")
			(remove_unused_layers no)
			(net "P2E_CPU_ETH10G_RX_DP10")
			(clearance 0.1778)
			(thermal_gap 0.1778)
		)
		(pad "A74" thru_hole circle
			(at 63.35014 -3.24993 180)
			(size 1.0922 1.0922)
			(drill 0.7366)
			(layers "*.Cu" "*.Mask")
			(remove_unused_layers no)
			(net "P2E_CPU_ETH10G_RX_DN10")
			(clearance 0.1778)
			(thermal_gap 0.1778)
		)
		(pad "A75" thru_hole circle
			(at 64.34963 -1.24968 180)
			(size 1.0922 1.0922)
			(drill 0.7366)
			(layers "*.Cu" "*.Mask")
			(remove_unused_layers no)
			(net "GND")
			(clearance 0.1778)
			(thermal_gap 0.1778)
		)
		(pad "A76" thru_hole circle
			(at 65.35039 -3.24993 180)
			(size 1.0922 1.0922)
			(drill 0.7366)
			(layers "*.Cu" "*.Mask")
			(remove_unused_layers no)
			(net "GND")
			(clearance 0.1778)
			(thermal_gap 0.1778)
		)
		(pad "A77" thru_hole circle
			(at 66.34988 -1.24968 180)
			(size 1.0922 1.0922)
			(drill 0.7366)
			(layers "*.Cu" "*.Mask")
			(remove_unused_layers no)
			(net "P2E_CPU_ETH10G_RX_DP11")
			(clearance 0.1778)
			(thermal_gap 0.1778)
		)
		(pad "A78" thru_hole circle
			(at 67.34937 -3.24993 180)
			(size 1.0922 1.0922)
			(drill 0.7366)
			(layers "*.Cu" "*.Mask")
			(remove_unused_layers no)
			(net "P2E_CPU_ETH10G_RX_DN11")
			(clearance 0.1778)
			(thermal_gap 0.1778)
		)
		(pad "A79" thru_hole circle
			(at 68.35013 -1.24968 180)
			(size 1.0922 1.0922)
			(drill 0.7366)
			(layers "*.Cu" "*.Mask")
			(remove_unused_layers no)
			(net "GND")
			(clearance 0.1778)
			(thermal_gap 0.1778)
		)
		(pad "A80" thru_hole circle
			(at 69.34962 -3.24993 180)
			(size 1.0922 1.0922)
			(drill 0.7366)
			(layers "*.Cu" "*.Mask")
			(remove_unused_layers no)
			(net "GND")
			(clearance 0.1778)
			(thermal_gap 0.1778)
		)
		(pad "A81" thru_hole circle
			(at 70.35038 -1.24968 180)
			(size 1.0922 1.0922)
			(drill 0.7366)
			(layers "*.Cu" "*.Mask")
			(remove_unused_layers no)
			(net "P12V")
			(clearance 0.1778)
			(thermal_gap 0.1778)
		)
		(pad "A82" thru_hole circle
			(at 71.34987 -3.24993 180)
			(size 1.0922 1.0922)
			(drill 0.7366)
			(layers "*.Cu" "*.Mask")
			(remove_unused_layers no)
			(net "P12V")
			(clearance 0.1778)
			(thermal_gap 0.1778)
		)
		(pad "B1" thru_hole circle
			(at -11.64971 1.24968 180)
			(size 1.0922 1.0922)
			(drill 0.7366)
			(layers "*.Cu" "*.Mask")
			(remove_unused_layers no)
			(net "P12V")
			(clearance 0.1778)
			(thermal_gap 0.1778)
		)
		(pad "B2" thru_hole circle
			(at -10.65022 3.24993 180)
			(size 1.0922 1.0922)
			(drill 0.7366)
			(layers "*.Cu" "*.Mask")
			(remove_unused_layers no)
			(net "P12V")
			(clearance 0.1778)
			(thermal_gap 0.1778)
		)
		(pad "B3" thru_hole circle
			(at -9.64946 1.24968 180)
			(size 1.0922 1.0922)
			(drill 0.7366)
			(layers "*.Cu" "*.Mask")
			(remove_unused_layers no)
			(net "P12V")
			(clearance 0.1778)
			(thermal_gap 0.1778)
		)
		(pad "B4" thru_hole circle
			(at -8.64997 3.24993 180)
			(size 1.0922 1.0922)
			(drill 0.7366)
			(layers "*.Cu" "*.Mask")
			(remove_unused_layers no)
			(net "GND")
			(clearance 0.1778)
			(thermal_gap 0.1778)
		)
		(pad "B5" thru_hole circle
			(at -7.65048 1.24968 180)
			(size 1.0922 1.0922)
			(drill 0.7366)
			(layers "*.Cu" "*.Mask")
			(remove_unused_layers no)
			(net "BMC_I2C_CLK")
			(clearance 0.1778)
			(thermal_gap 0.1778)
		)
		(pad "B6" thru_hole circle
			(at -6.64972 3.24993 180)
			(size 1.0922 1.0922)
			(drill 0.7366)
			(layers "*.Cu" "*.Mask")
			(remove_unused_layers no)
			(net "BMC_I2C_DATA")
			(clearance 0.1778)
			(thermal_gap 0.1778)
		)
		(pad "B7" thru_hole circle
			(at -5.65023 1.24968 180)
			(size 1.0922 1.0922)
			(drill 0.7366)
			(layers "*.Cu" "*.Mask")
			(remove_unused_layers no)
			(net "GND")
			(clearance 0.1778)
			(thermal_gap 0.1778)
		)
		(pad "B8" thru_hole circle
			(at -4.64947 3.24993 180)
			(size 1.0922 1.0922)
			(drill 0.7366)
			(layers "*.Cu" "*.Mask")
			(remove_unused_layers no)
			(net "PMU_PWRBTN#")
			(clearance 0.1778)
			(thermal_gap 0.1778)
		)
		(pad "B9" thru_hole circle
			(at -3.64998 1.24968 180)
			(size 1.0922 1.0922)
			(drill 0.7366)
			(layers "*.Cu" "*.Mask")
			(remove_unused_layers no)
			(net "USB_P1_DP")
			(clearance 0.1778)
			(thermal_gap 0.1778)
		)
		(pad "B10" thru_hole circle
			(at -2.65049 3.24993 180)
			(size 1.0922 1.0922)
			(drill 0.7366)
			(layers "*.Cu" "*.Mask")
			(remove_unused_layers no)
			(net "USB_P1_DN")
			(clearance 0.1778)
			(thermal_gap 0.1778)
		)
		(pad "B11" thru_hole circle
			(at -1.64973 1.24968 180)
			(size 1.0922 1.0922)
			(drill 0.7366)
			(layers "*.Cu" "*.Mask")
			(remove_unused_layers no)
			(net "BMC_SYS_RESET#")
			(clearance 0.1778)
			(thermal_gap 0.1778)
		)
		(pad "B12" thru_hole circle
			(at 1.35001 3.24993 180)
			(size 1.0922 1.0922)
			(drill 0.7366)
			(layers "*.Cu" "*.Mask")
			(remove_unused_layers no)
			(net "BMC_I2C_ALERT#")
			(clearance 0.1778)
			(thermal_gap 0.1778)
		)
		(pad "B13" thru_hole circle
			(at 2.3495 1.24968 180)
			(size 1.0922 1.0922)
			(drill 0.7366)
			(layers "*.Cu" "*.Mask")
			(remove_unused_layers no)
			(net "GND")
			(clearance 0.1778)
			(thermal_gap 0.1778)
		)
		(pad "B14" thru_hole circle
			(at 3.35026 3.24993 180)
			(size 1.0922 1.0922)
			(drill 0.7366)
			(layers "*.Cu" "*.Mask")
			(remove_unused_layers no)
			(net "GND")
			(clearance 0.1778)
			(thermal_gap 0.1778)
		)
		(pad "B15" thru_hole circle
			(at 4.34975 1.24968 180)
			(size 1.0922 1.0922)
			(drill 0.7366)
			(layers "*.Cu" "*.Mask")
			(remove_unused_layers no)
			(net "P2E_CPU_SAS_TX_DP0")
			(clearance 0.1778)
			(thermal_gap 0.1778)
		)
		(pad "B16" thru_hole circle
			(at 5.35051 3.24993 180)
			(size 1.0922 1.0922)
			(drill 0.7366)
			(layers "*.Cu" "*.Mask")
			(remove_unused_layers no)
			(net "P2E_CPU_SAS_TX_DN0")
			(clearance 0.1778)
			(thermal_gap 0.1778)
		)
		(pad "B17" thru_hole circle
			(at 6.35 1.24968 180)
			(size 1.0922 1.0922)
			(drill 0.7366)
			(layers "*.Cu" "*.Mask")
			(remove_unused_layers no)
			(net "GND")
			(clearance 0.1778)
			(thermal_gap 0.1778)
		)
		(pad "B18" thru_hole circle
			(at 7.34949 3.24993 180)
			(size 1.0922 1.0922)
			(drill 0.7366)
			(layers "*.Cu" "*.Mask")
			(remove_unused_layers no)
			(net "GND")
			(clearance 0.1778)
			(thermal_gap 0.1778)
		)
		(pad "B19" thru_hole circle
			(at 8.35025 1.24968 180)
			(size 1.0922 1.0922)
			(drill 0.7366)
			(layers "*.Cu" "*.Mask")
			(remove_unused_layers no)
			(net "P2E_CPU_SAS_TX_DP1")
			(clearance 0.1778)
			(thermal_gap 0.1778)
		)
		(pad "B20" thru_hole circle
			(at 9.34974 3.24993 180)
			(size 1.0922 1.0922)
			(drill 0.7366)
			(layers "*.Cu" "*.Mask")
			(remove_unused_layers no)
			(net "P2E_CPU_SAS_TX_DN1")
			(clearance 0.1778)
			(thermal_gap 0.1778)
		)
		(pad "B21" thru_hole circle
			(at 10.3505 1.24968 180)
			(size 1.0922 1.0922)
			(drill 0.7366)
			(layers "*.Cu" "*.Mask")
			(remove_unused_layers no)
			(net "GND")
			(clearance 0.1778)
			(thermal_gap 0.1778)
		)
		(pad "B22" thru_hole circle
			(at 11.34999 3.24993 180)
			(size 1.0922 1.0922)
			(drill 0.7366)
			(layers "*.Cu" "*.Mask")
			(remove_unused_layers no)
			(net "GND")
			(clearance 0.1778)
			(thermal_gap 0.1778)
		)
		(pad "B23" thru_hole circle
			(at 12.34948 1.24968 180)
			(size 1.0922 1.0922)
			(drill 0.7366)
			(layers "*.Cu" "*.Mask")
			(remove_unused_layers no)
			(net "P2E_CPU_SAS_TX_DP2")
			(clearance 0.1778)
			(thermal_gap 0.1778)
		)
		(pad "B24" thru_hole circle
			(at 13.35024 3.24993 180)
			(size 1.0922 1.0922)
			(drill 0.7366)
			(layers "*.Cu" "*.Mask")
			(remove_unused_layers no)
			(net "P2E_CPU_SAS_TX_DN2")
			(clearance 0.1778)
			(thermal_gap 0.1778)
		)
		(pad "B25" thru_hole circle
			(at 14.34973 1.24968 180)
			(size 1.0922 1.0922)
			(drill 0.7366)
			(layers "*.Cu" "*.Mask")
			(remove_unused_layers no)
			(net "GND")
			(clearance 0.1778)
			(thermal_gap 0.1778)
		)
		(pad "B26" thru_hole circle
			(at 15.35049 3.24993 180)
			(size 1.0922 1.0922)
			(drill 0.7366)
			(layers "*.Cu" "*.Mask")
			(remove_unused_layers no)
			(net "GND")
			(clearance 0.1778)
			(thermal_gap 0.1778)
		)
		(pad "B27" thru_hole circle
			(at 16.34998 1.24968 180)
			(size 1.0922 1.0922)
			(drill 0.7366)
			(layers "*.Cu" "*.Mask")
			(remove_unused_layers no)
			(net "P2E_CPU_SAS_TX_DP3")
			(clearance 0.1778)
			(thermal_gap 0.1778)
		)
		(pad "B28" thru_hole circle
			(at 17.34947 3.24993 180)
			(size 1.0922 1.0922)
			(drill 0.7366)
			(layers "*.Cu" "*.Mask")
			(remove_unused_layers no)
			(net "P2E_CPU_SAS_TX_DN3")
			(clearance 0.1778)
			(thermal_gap 0.1778)
		)
		(pad "B29" thru_hole circle
			(at 18.35023 1.24968 180)
			(size 1.0922 1.0922)
			(drill 0.7366)
			(layers "*.Cu" "*.Mask")
			(remove_unused_layers no)
			(net "GND")
			(clearance 0.1778)
			(thermal_gap 0.1778)
		)
		(pad "B30" thru_hole circle
			(at 19.34972 3.24993 180)
			(size 1.0922 1.0922)
			(drill 0.7366)
			(layers "*.Cu" "*.Mask")
			(remove_unused_layers no)
			(net "GND")
			(clearance 0.1778)
			(thermal_gap 0.1778)
		)
		(pad "B31" thru_hole circle
			(at 20.35048 1.24968 180)
			(size 1.0922 1.0922)
			(drill 0.7366)
			(layers "*.Cu" "*.Mask")
			(remove_unused_layers no)
			(net "SATA2_TX_C_DP0")
			(clearance 0.1778)
			(thermal_gap 0.1778)
		)
		(pad "B32" thru_hole circle
			(at 21.34997 3.24993 180)
			(size 1.0922 1.0922)
			(drill 0.7366)
			(layers "*.Cu" "*.Mask")
			(remove_unused_layers no)
			(net "SATA2_TX_C_DN0")
			(clearance 0.1778)
			(thermal_gap 0.1778)
		)
		(pad "B33" thru_hole circle
			(at 22.34946 1.24968 180)
			(size 1.0922 1.0922)
			(drill 0.7366)
			(layers "*.Cu" "*.Mask")
			(remove_unused_layers no)
			(net "GND")
			(clearance 0.1778)
			(thermal_gap 0.1778)
		)
		(pad "B34" thru_hole circle
			(at 23.35022 3.24993 180)
			(size 1.0922 1.0922)
			(drill 0.7366)
			(layers "*.Cu" "*.Mask")
			(remove_unused_layers no)
			(net "GND")
			(clearance 0.1778)
			(thermal_gap 0.1778)
		)
		(pad "B35" thru_hole circle
			(at 24.34971 1.24968 180)
			(size 1.0922 1.0922)
			(drill 0.7366)
			(layers "*.Cu" "*.Mask")
			(remove_unused_layers no)
			(net "CLK_100M_CLKBUFF_ENET_DP")
			(clearance 0.1778)
			(thermal_gap 0.1778)
		)
		(pad "B36" thru_hole circle
			(at 25.35047 3.24993 180)
			(size 1.0922 1.0922)
			(drill 0.7366)
			(layers "*.Cu" "*.Mask")
			(remove_unused_layers no)
			(net "CLK_100M_CLKBUFF_ENET_DN")
			(clearance 0.1778)
			(thermal_gap 0.1778)
		)
		(pad "B37" thru_hole circle
			(at 26.34996 1.24968 180)
			(size 1.0922 1.0922)
			(drill 0.7366)
			(layers "*.Cu" "*.Mask")
			(remove_unused_layers no)
			(net "GND")
			(clearance 0.1778)
			(thermal_gap 0.1778)
		)
		(pad "B38" thru_hole circle
			(at 27.34945 3.24993 180)
			(size 1.0922 1.0922)
			(drill 0.7366)
			(layers "*.Cu" "*.Mask")
			(remove_unused_layers no)
			(net "GND")
			(clearance 0.1778)
			(thermal_gap 0.1778)
		)
		(pad "B39" thru_hole circle
			(at 28.35021 1.24968 180)
			(size 1.0922 1.0922)
			(drill 0.7366)
			(layers "*.Cu" "*.Mask")
			(remove_unused_layers no)
			(net "PCIE1_RESET#")
			(clearance 0.1778)
			(thermal_gap 0.1778)
		)
		(pad "B40" thru_hole circle
			(at 29.3497 3.24993 180)
			(size 1.0922 1.0922)
			(drill 0.7366)
			(layers "*.Cu" "*.Mask")
			(remove_unused_layers no)
			(net "PCIE_RSVD_B40")
			(clearance 0.1778)
			(thermal_gap 0.1778)
		)
		(pad "B41" thru_hole circle
			(at 30.35046 1.24968 180)
			(size 1.0922 1.0922)
			(drill 0.7366)
			(layers "*.Cu" "*.Mask")
			(remove_unused_layers no)
			(net "GND")
			(clearance 0.1778)
			(thermal_gap 0.1778)
		)
		(pad "B42" thru_hole circle
			(at 31.34995 3.24993 180)
			(size 1.0922 1.0922)
			(drill 0.7366)
			(layers "*.Cu" "*.Mask")
			(remove_unused_layers no)
			(net "GND")
			(clearance 0.1778)
			(thermal_gap 0.1778)
		)
		(pad "B43" thru_hole circle
			(at 32.34944 1.24968 180)
			(size 1.0922 1.0922)
			(drill 0.7366)
			(layers "*.Cu" "*.Mask")
			(remove_unused_layers no)
			(net "GBE_SMBCLK_R")
			(clearance 0.1778)
			(thermal_gap 0.1778)
		)
		(pad "B44" thru_hole circle
			(at 33.3502 3.24993 180)
			(size 1.0922 1.0922)
			(drill 0.7366)
			(layers "*.Cu" "*.Mask")
			(remove_unused_layers no)
			(net "GBE_SMDATA_R")
			(clearance 0.1778)
			(thermal_gap 0.1778)
		)
		(pad "B45" thru_hole circle
			(at 34.34969 1.24968 180)
			(size 1.0922 1.0922)
			(drill 0.7366)
			(layers "*.Cu" "*.Mask")
			(remove_unused_layers no)
			(net "GND")
			(clearance 0.1778)
			(thermal_gap 0.1778)
		)
		(pad "B46" thru_hole circle
			(at 35.35045 3.24993 180)
			(size 1.0922 1.0922)
			(drill 0.7366)
			(layers "*.Cu" "*.Mask")
			(remove_unused_layers no)
			(net "GND")
			(clearance 0.1778)
			(thermal_gap 0.1778)
		)
		(pad "B47" thru_hole circle
			(at 36.34994 1.24968 180)
			(size 1.0922 1.0922)
			(drill 0.7366)
			(layers "*.Cu" "*.Mask")
			(remove_unused_layers no)
			(net "CPU_GBE_TX_C_DP0")
			(clearance 0.1778)
			(thermal_gap 0.1778)
		)
		(pad "B48" thru_hole circle
			(at 37.34943 3.24993 180)
			(size 1.0922 1.0922)
			(drill 0.7366)
			(layers "*.Cu" "*.Mask")
			(remove_unused_layers no)
			(net "CPU_GBE_TX_C_DN0")
			(clearance 0.1778)
			(thermal_gap 0.1778)
		)
		(pad "B49" thru_hole circle
			(at 38.35019 1.24968 180)
			(size 1.0922 1.0922)
			(drill 0.7366)
			(layers "*.Cu" "*.Mask")
			(remove_unused_layers no)
			(net "GND")
			(clearance 0.1778)
			(thermal_gap 0.1778)
		)
		(pad "B50" thru_hole circle
			(at 39.34968 3.24993 180)
			(size 1.0922 1.0922)
			(drill 0.7366)
			(layers "*.Cu" "*.Mask")
			(remove_unused_layers no)
			(net "GND")
			(clearance 0.1778)
			(thermal_gap 0.1778)
		)
		(pad "B51" thru_hole circle
			(at 40.35044 1.24968 180)
			(size 1.0922 1.0922)
			(drill 0.7366)
			(layers "*.Cu" "*.Mask")
			(remove_unused_layers no)
			(net "P2E_CPU_SAS_TX_DP4")
			(clearance 0.1778)
			(thermal_gap 0.1778)
		)
		(pad "B52" thru_hole circle
			(at 41.34993 3.24993 180)
			(size 1.0922 1.0922)
			(drill 0.7366)
			(layers "*.Cu" "*.Mask")
			(remove_unused_layers no)
			(net "P2E_CPU_SAS_TX_DN4")
			(clearance 0.1778)
			(thermal_gap 0.1778)
		)
		(pad "B53" thru_hole circle
			(at 42.34942 1.24968 180)
			(size 1.0922 1.0922)
			(drill 0.7366)
			(layers "*.Cu" "*.Mask")
			(remove_unused_layers no)
			(net "GND")
			(clearance 0.1778)
			(thermal_gap 0.1778)
		)
		(pad "B54" thru_hole circle
			(at 43.35018 3.24993 180)
			(size 1.0922 1.0922)
			(drill 0.7366)
			(layers "*.Cu" "*.Mask")
			(remove_unused_layers no)
			(net "GND")
			(clearance 0.1778)
			(thermal_gap 0.1778)
		)
		(pad "B55" thru_hole circle
			(at 44.34967 1.24968 180)
			(size 1.0922 1.0922)
			(drill 0.7366)
			(layers "*.Cu" "*.Mask")
			(remove_unused_layers no)
			(net "P2E_CPU_SAS_TX_DP5")
			(clearance 0.1778)
			(thermal_gap 0.1778)
		)
		(pad "B56" thru_hole circle
			(at 45.35043 3.24993 180)
			(size 1.0922 1.0922)
			(drill 0.7366)
			(layers "*.Cu" "*.Mask")
			(remove_unused_layers no)
			(net "P2E_CPU_SAS_TX_DN5")
			(clearance 0.1778)
			(thermal_gap 0.1778)
		)
		(pad "B57" thru_hole circle
			(at 46.34992 1.24968 180)
			(size 1.0922 1.0922)
			(drill 0.7366)
			(layers "*.Cu" "*.Mask")
			(remove_unused_layers no)
			(net "GND")
			(clearance 0.1778)
			(thermal_gap 0.1778)
		)
		(pad "B58" thru_hole circle
			(at 47.34941 3.24993 180)
			(size 1.0922 1.0922)
			(drill 0.7366)
			(layers "*.Cu" "*.Mask")
			(remove_unused_layers no)
			(net "GND")
			(clearance 0.1778)
			(thermal_gap 0.1778)
		)
		(pad "B59" thru_hole circle
			(at 48.35017 1.24968 180)
			(size 1.0922 1.0922)
			(drill 0.7366)
			(layers "*.Cu" "*.Mask")
			(remove_unused_layers no)
			(net "P2E_CPU_SAS_TX_DP6")
			(clearance 0.1778)
			(thermal_gap 0.1778)
		)
		(pad "B60" thru_hole circle
			(at 49.34966 3.24993 180)
			(size 1.0922 1.0922)
			(drill 0.7366)
			(layers "*.Cu" "*.Mask")
			(remove_unused_layers no)
			(net "P2E_CPU_SAS_TX_DN6")
			(clearance 0.1778)
			(thermal_gap 0.1778)
		)
		(pad "B61" thru_hole circle
			(at 50.35042 1.24968 180)
			(size 1.0922 1.0922)
			(drill 0.7366)
			(layers "*.Cu" "*.Mask")
			(remove_unused_layers no)
			(net "GND")
			(clearance 0.1778)
			(thermal_gap 0.1778)
		)
		(pad "B62" thru_hole circle
			(at 51.34991 3.24993 180)
			(size 1.0922 1.0922)
			(drill 0.7366)
			(layers "*.Cu" "*.Mask")
			(remove_unused_layers no)
			(net "GND")
			(clearance 0.1778)
			(thermal_gap 0.1778)
		)
		(pad "B63" thru_hole circle
			(at 52.3494 1.24968 180)
			(size 1.0922 1.0922)
			(drill 0.7366)
			(layers "*.Cu" "*.Mask")
			(remove_unused_layers no)
			(net "P2E_CPU_SAS_TX_DP7")
			(clearance 0.1778)
			(thermal_gap 0.1778)
		)
		(pad "B64" thru_hole circle
			(at 53.35016 3.24993 180)
			(size 1.0922 1.0922)
			(drill 0.7366)
			(layers "*.Cu" "*.Mask")
			(remove_unused_layers no)
			(net "P2E_CPU_SAS_TX_DN7")
			(clearance 0.1778)
			(thermal_gap 0.1778)
		)
		(pad "B65" thru_hole circle
			(at 54.34965 1.24968 180)
			(size 1.0922 1.0922)
			(drill 0.7366)
			(layers "*.Cu" "*.Mask")
			(remove_unused_layers no)
			(net "GND")
			(clearance 0.1778)
			(thermal_gap 0.1778)
		)
		(pad "B66" thru_hole circle
			(at 55.35041 3.24993 180)
			(size 1.0922 1.0922)
			(drill 0.7366)
			(layers "*.Cu" "*.Mask")
			(remove_unused_layers no)
			(net "GND")
			(clearance 0.1778)
			(thermal_gap 0.1778)
		)
		(pad "B67" thru_hole circle
			(at 56.3499 1.24968 180)
			(size 1.0922 1.0922)
			(drill 0.7366)
			(layers "*.Cu" "*.Mask")
			(remove_unused_layers no)
			(net "P2E_CPU_ETH10G_TX_DP8")
			(clearance 0.1778)
			(thermal_gap 0.1778)
		)
		(pad "B68" thru_hole circle
			(at 57.34939 3.24993 180)
			(size 1.0922 1.0922)
			(drill 0.7366)
			(layers "*.Cu" "*.Mask")
			(remove_unused_layers no)
			(net "P2E_CPU_ETH10G_TX_DN8")
			(clearance 0.1778)
			(thermal_gap 0.1778)
		)
		(pad "B69" thru_hole circle
			(at 58.35015 1.24968 180)
			(size 1.0922 1.0922)
			(drill 0.7366)
			(layers "*.Cu" "*.Mask")
			(remove_unused_layers no)
			(net "GND")
			(clearance 0.1778)
			(thermal_gap 0.1778)
		)
		(pad "B70" thru_hole circle
			(at 59.34964 3.24993 180)
			(size 1.0922 1.0922)
			(drill 0.7366)
			(layers "*.Cu" "*.Mask")
			(remove_unused_layers no)
			(net "GND")
			(clearance 0.1778)
			(thermal_gap 0.1778)
		)
		(pad "B71" thru_hole circle
			(at 60.3504 1.24968 180)
			(size 1.0922 1.0922)
			(drill 0.7366)
			(layers "*.Cu" "*.Mask")
			(remove_unused_layers no)
			(net "P2E_CPU_ETH10G_TX_DP9")
			(clearance 0.1778)
			(thermal_gap 0.1778)
		)
		(pad "B72" thru_hole circle
			(at 61.34989 3.24993 180)
			(size 1.0922 1.0922)
			(drill 0.7366)
			(layers "*.Cu" "*.Mask")
			(remove_unused_layers no)
			(net "P2E_CPU_ETH10G_TX_DN9")
			(clearance 0.1778)
			(thermal_gap 0.1778)
		)
		(pad "B73" thru_hole circle
			(at 62.34938 1.24968 180)
			(size 1.0922 1.0922)
			(drill 0.7366)
			(layers "*.Cu" "*.Mask")
			(remove_unused_layers no)
			(net "GND")
			(clearance 0.1778)
			(thermal_gap 0.1778)
		)
		(pad "B74" thru_hole circle
			(at 63.35014 3.24993 180)
			(size 1.0922 1.0922)
			(drill 0.7366)
			(layers "*.Cu" "*.Mask")
			(remove_unused_layers no)
			(net "GND")
			(clearance 0.1778)
			(thermal_gap 0.1778)
		)
		(pad "B75" thru_hole circle
			(at 64.34963 1.24968 180)
			(size 1.0922 1.0922)
			(drill 0.7366)
			(layers "*.Cu" "*.Mask")
			(remove_unused_layers no)
			(net "P2E_CPU_ETH10G_TX_DP10")
			(clearance 0.1778)
			(thermal_gap 0.1778)
		)
		(pad "B76" thru_hole circle
			(at 65.35039 3.24993 180)
			(size 1.0922 1.0922)
			(drill 0.7366)
			(layers "*.Cu" "*.Mask")
			(remove_unused_layers no)
			(net "P2E_CPU_ETH10G_TX_DN10")
			(clearance 0.1778)
			(thermal_gap 0.1778)
		)
		(pad "B77" thru_hole circle
			(at 66.34988 1.24968 180)
			(size 1.0922 1.0922)
			(drill 0.7366)
			(layers "*.Cu" "*.Mask")
			(remove_unused_layers no)
			(net "GND")
			(clearance 0.1778)
			(thermal_gap 0.1778)
		)
		(pad "B78" thru_hole circle
			(at 67.34937 3.24993 180)
			(size 1.0922 1.0922)
			(drill 0.7366)
			(layers "*.Cu" "*.Mask")
			(remove_unused_layers no)
			(net "GND")
			(clearance 0.1778)
			(thermal_gap 0.1778)
		)
		(pad "B79" thru_hole circle
			(at 68.35013 1.24968 180)
			(size 1.0922 1.0922)
			(drill 0.7366)
			(layers "*.Cu" "*.Mask")
			(remove_unused_layers no)
			(net "P2E_CPU_ETH10G_TX_DP11")
			(clearance 0.1778)
			(thermal_gap 0.1778)
		)
		(pad "B80" thru_hole circle
			(at 69.34962 3.24993 180)
			(size 1.0922 1.0922)
			(drill 0.7366)
			(layers "*.Cu" "*.Mask")
			(remove_unused_layers no)
			(net "P2E_CPU_ETH10G_TX_DN11")
			(clearance 0.1778)
			(thermal_gap 0.1778)
		)
		(pad "B81" thru_hole circle
			(at 70.35038 1.24968 180)
			(size 1.0922 1.0922)
			(drill 0.7366)
			(layers "*.Cu" "*.Mask")
			(remove_unused_layers no)
			(net "GND")
			(clearance 0.1778)
			(thermal_gap 0.1778)
		)
		(pad "B82" thru_hole circle
			(at 71.34987 3.24993 180)
			(size 1.0922 1.0922)
			(drill 0.7366)
			(layers "*.Cu" "*.Mask")
			(remove_unused_layers no)
			(net "GND")
			(clearance 0.1778)
			(thermal_gap 0.1778)
		)
		(zone
			(layers "F.Cu" "B.Cu" "In1.Cu" "In2.Cu")
			(hatch none 0.5)
			(connect_pads
				(clearance 0)
			)
			(min_thickness 0.25)
			(keepout
				(tracks not_allowed)
				(vias allowed)
				(pads allowed)
				(copperpour not_allowed)
				(footprints allowed)
			)
			(placement
				(enabled no)
				(sheetname "")
			)
			(fill
				(thermal_gap 0.5)
				(thermal_bridge_width 0.5)
				(island_removal_mode 0)
			)
			(polygon
				(pts
					(arc
						(start 5.686552 -19.899884)
						(mid 2.714752 -19.899884)
						(end 5.686552 -19.899884)
					)
				)
			)
		)
		(zone
			(layers "F.Cu" "B.Cu" "In1.Cu" "In2.Cu")
			(hatch none 0.5)
			(connect_pads
				(clearance 0)
			)
			(min_thickness 0.25)
			(keepout
				(tracks not_allowed)
				(vias allowed)
				(pads allowed)
				(copperpour not_allowed)
				(footprints allowed)
			)
			(placement
				(enabled no)
				(sheetname "")
			)
			(fill
				(thermal_gap 0.5)
				(thermal_bridge_width 0.5)
				(island_removal_mode 0)
			)
			(polygon
				(pts
					(arc
						(start 78.836012 -19.899884)
						(mid 75.864212 -19.899884)
						(end 78.836012 -19.899884)
					)
				)
			)
		)
	)
	(gr_line
		(start 9.99998 -5.747004)
		(end 10.255758 -6.002782)
		(stroke
			(width 0.06985)
			(type default)
		)
		(layer "F.Cu")
	)
	(gr_line
		(start 9.99998 -3.495548)
		(end 9.99998 -5.747004)
		(stroke
			(width 0.06985)
			(type default)
		)
		(layer "F.Cu")
	)
	(gr_line
		(start 10.000488 -17.133316)
		(end 10.301732 -17.43456)
		(stroke
			(width 0.06985)
			(type default)
		)
		(layer "F.Cu")
	)
	(gr_line
		(start 10.000488 -16.649954)
		(end 10.000488 -17.133316)
		(stroke
			(width 0.06985)
			(type default)
		)
		(layer "F.Cu")
	)
	(gr_line
		(start 10.000488 -16.649954)
		(end 10.000742 -16.649954)
		(stroke
			(width 0.06985)
			(type default)
		)
		(layer "F.Cu")
	)
	(gr_line
		(start 10.301732 -17.43456)
		(end 10.61466 -17.43456)
		(stroke
			(width 0.06985)
			(type default)
		)
		(layer "F.Cu")
	)
	(gr_line
		(start 10.6172 -17.43456)
		(end 10.634472 -17.43456)
		(stroke
			(width 0.06985)
			(type default)
		)
		(layer "F.Cu")
	)
	(gr_line
		(start 10.744454 -6.002782)
		(end 10.999978 -5.747258)
		(stroke
			(width 0.06985)
			(type default)
		)
		(layer "F.Cu")
	)
	(gr_line
		(start 10.9601 -18.610072)
		(end 11.000232 -18.650204)
		(stroke
			(width 0.06985)
			(type default)
		)
		(layer "F.Cu")
	)
	(gr_line
		(start 10.9601 -17.78)
		(end 10.9601 -18.610072)
		(stroke
			(width 0.06985)
			(type default)
		)
		(layer "F.Cu")
	)
	(gr_line
		(start 10.9601 -17.594072)
		(end 10.9601 -17.77746)
		(stroke
			(width 0.06985)
			(type default)
		)
		(layer "F.Cu")
	)
	(gr_line
		(start 10.999978 -3.495548)
		(end 10.999978 -5.747258)
		(stroke
			(width 0.06985)
			(type default)
		)
		(layer "F.Cu")
	)
	(gr_line
		(start 13.999718 -17.133316)
		(end 14.285722 -17.41932)
		(stroke
			(width 0.06985)
			(type default)
		)
		(layer "F.Cu")
	)
	(gr_line
		(start 13.999718 -16.649954)
		(end 13.999718 -17.133316)
		(stroke
			(width 0.06985)
			(type default)
		)
		(layer "F.Cu")
	)
	(gr_line
		(start 13.999718 -16.649954)
		(end 13.999972 -16.649954)
		(stroke
			(width 0.06985)
			(type default)
		)
		(layer "F.Cu")
	)
	(gr_line
		(start 13.999972 -5.747004)
		(end 14.25575 -6.002782)
		(stroke
			(width 0.06985)
			(type default)
		)
		(layer "F.Cu")
	)
	(gr_line
		(start 13.999972 -3.495548)
		(end 13.999972 -5.747004)
		(stroke
			(width 0.06985)
			(type default)
		)
		(layer "F.Cu")
	)
	(gr_line
		(start 14.285722 -17.41932)
		(end 14.648942 -17.41932)
		(stroke
			(width 0.06985)
			(type default)
		)
		(layer "F.Cu")
	)
	(gr_line
		(start 14.744446 -6.002782)
		(end 14.99997 -5.747258)
		(stroke
			(width 0.06985)
			(type default)
		)
		(layer "F.Cu")
	)
	(gr_line
		(start 14.99997 -3.495548)
		(end 14.99997 -5.747258)
		(stroke
			(width 0.06985)
			(type default)
		)
		(layer "F.Cu")
	)
	(gr_line
		(start 15.000478 -18.650204)
		(end 15.000732 -18.650204)
		(stroke
			(width 0.06985)
			(type default)
		)
		(layer "F.Cu")
	)
	(gr_line
		(start 15.000478 -17.556226)
		(end 15.000478 -18.650204)
		(stroke
			(width 0.06985)
			(type default)
		)
		(layer "F.Cu")
	)
	(gr_line
		(start 17.999964 -5.747004)
		(end 18.255742 -6.002782)
		(stroke
			(width 0.06985)
			(type default)
		)
		(layer "F.Cu")
	)
	(gr_line
		(start 17.999964 -3.495548)
		(end 17.999964 -5.747004)
		(stroke
			(width 0.06985)
			(type default)
		)
		(layer "F.Cu")
	)
	(gr_line
		(start 18.000218 -17.134586)
		(end 18.292572 -17.42694)
		(stroke
			(width 0.06985)
			(type default)
		)
		(layer "F.Cu")
	)
	(gr_line
		(start 18.000218 -16.649954)
		(end 18.000218 -17.134586)
		(stroke
			(width 0.06985)
			(type default)
		)
		(layer "F.Cu")
	)
	(gr_line
		(start 18.000218 -16.649954)
		(end 18.000472 -16.649954)
		(stroke
			(width 0.06985)
			(type default)
		)
		(layer "F.Cu")
	)
	(gr_line
		(start 18.292572 -17.42694)
		(end 18.60296 -17.42694)
		(stroke
			(width 0.06985)
			(type default)
		)
		(layer "F.Cu")
	)
	(gr_line
		(start 18.6055 -17.42694)
		(end 18.640552 -17.42694)
		(stroke
			(width 0.06985)
			(type default)
		)
		(layer "F.Cu")
	)
	(gr_line
		(start 18.744438 -6.002782)
		(end 18.999962 -5.747258)
		(stroke
			(width 0.06985)
			(type default)
		)
		(layer "F.Cu")
	)
	(gr_line
		(start 18.9484 -18.598642)
		(end 18.999962 -18.650204)
		(stroke
			(width 0.06985)
			(type default)
		)
		(layer "F.Cu")
	)
	(gr_line
		(start 18.9484 -17.77238)
		(end 18.9484 -18.598642)
		(stroke
			(width 0.06985)
			(type default)
		)
		(layer "F.Cu")
	)
	(gr_line
		(start 18.9484 -17.604232)
		(end 18.9484 -17.76984)
		(stroke
			(width 0.06985)
			(type default)
		)
		(layer "F.Cu")
	)
	(gr_line
		(start 18.999962 -3.495548)
		(end 18.999962 -5.747258)
		(stroke
			(width 0.06985)
			(type default)
		)
		(layer "F.Cu")
	)
	(gr_line
		(start 21.999448 -17.134586)
		(end 22.299422 -17.43456)
		(stroke
			(width 0.06985)
			(type default)
		)
		(layer "F.Cu")
	)
	(gr_line
		(start 21.999448 -16.649954)
		(end 21.999448 -17.134586)
		(stroke
			(width 0.06985)
			(type default)
		)
		(layer "F.Cu")
	)
	(gr_line
		(start 21.999448 -16.649954)
		(end 21.999702 -16.649954)
		(stroke
			(width 0.06985)
			(type default)
		)
		(layer "F.Cu")
	)
	(gr_line
		(start 21.999956 -5.747004)
		(end 22.255734 -6.002782)
		(stroke
			(width 0.06985)
			(type default)
		)
		(layer "F.Cu")
	)
	(gr_line
		(start 21.999956 -3.495548)
		(end 21.999956 -5.747004)
		(stroke
			(width 0.06985)
			(type default)
		)
		(layer "F.Cu")
	)
	(gr_line
		(start 22.299422 -17.43456)
		(end 22.6187 -17.43456)
		(stroke
			(width 0.06985)
			(type default)
		)
		(layer "F.Cu")
	)
	(gr_line
		(start 22.62124 -17.43456)
		(end 22.632162 -17.43456)
		(stroke
			(width 0.06985)
			(type default)
		)
		(layer "F.Cu")
	)
	(gr_line
		(start 22.74443 -6.002782)
		(end 22.999954 -5.747258)
		(stroke
			(width 0.06985)
			(type default)
		)
		(layer "F.Cu")
	)
	(gr_line
		(start 22.96414 -18.613882)
		(end 23.000462 -18.650204)
		(stroke
			(width 0.06985)
			(type default)
		)
		(layer "F.Cu")
	)
	(gr_line
		(start 22.96414 -17.78)
		(end 22.96414 -18.613882)
		(stroke
			(width 0.06985)
			(type default)
		)
		(layer "F.Cu")
	)
	(gr_line
		(start 22.96414 -17.587722)
		(end 22.96414 -17.77746)
		(stroke
			(width 0.06985)
			(type default)
		)
		(layer "F.Cu")
	)
	(gr_line
		(start 22.999954 -3.495548)
		(end 22.999954 -5.747258)
		(stroke
			(width 0.06985)
			(type default)
		)
		(layer "F.Cu")
	)
	(gr_line
		(start 25.999948 -17.134586)
		(end 26.264362 -17.399)
		(stroke
			(width 0.06985)
			(type default)
		)
		(layer "F.Cu")
	)
	(gr_line
		(start 25.999948 -16.649954)
		(end 25.999948 -17.134586)
		(stroke
			(width 0.06985)
			(type default)
		)
		(layer "F.Cu")
	)
	(gr_line
		(start 25.999948 -16.649954)
		(end 26.000202 -16.649954)
		(stroke
			(width 0.06985)
			(type default)
		)
		(layer "F.Cu")
	)
	(gr_line
		(start 25.999948 -5.747004)
		(end 26.255726 -6.002782)
		(stroke
			(width 0.06985)
			(type default)
		)
		(layer "F.Cu")
	)
	(gr_line
		(start 25.999948 -3.495548)
		(end 25.999948 -5.747004)
		(stroke
			(width 0.06985)
			(type default)
		)
		(layer "F.Cu")
	)
	(gr_line
		(start 26.264362 -17.399)
		(end 26.655268 -17.399)
		(stroke
			(width 0.06985)
			(type default)
		)
		(layer "F.Cu")
	)
	(gr_line
		(start 26.657808 -17.399)
		(end 26.668222 -17.399)
		(stroke
			(width 0.06985)
			(type default)
		)
		(layer "F.Cu")
	)
	(gr_line
		(start 26.744422 -6.002782)
		(end 26.999946 -5.747258)
		(stroke
			(width 0.06985)
			(type default)
		)
		(layer "F.Cu")
	)
	(gr_line
		(start 26.999438 -18.650204)
		(end 26.999692 -18.650204)
		(stroke
			(width 0.06985)
			(type default)
		)
		(layer "F.Cu")
	)
	(gr_line
		(start 26.999438 -18.650204)
		(end 27.000708 -18.648934)
		(stroke
			(width 0.06985)
			(type default)
		)
		(layer "F.Cu")
	)
	(gr_line
		(start 26.999946 -3.495548)
		(end 26.999946 -5.747258)
		(stroke
			(width 0.06985)
			(type default)
		)
		(layer "F.Cu")
	)
	(gr_line
		(start 27.000708 -17.74444)
		(end 27.000708 -18.648934)
		(stroke
			(width 0.06985)
			(type default)
		)
		(layer "F.Cu")
	)
	(gr_line
		(start 27.000708 -17.551654)
		(end 27.000708 -17.7419)
		(stroke
			(width 0.06985)
			(type default)
		)
		(layer "F.Cu")
	)
	(gr_line
		(start 29.99994 -5.747004)
		(end 30.255718 -6.002782)
		(stroke
			(width 0.06985)
			(type default)
		)
		(layer "F.Cu")
	)
	(gr_line
		(start 29.99994 -3.495548)
		(end 29.99994 -5.747004)
		(stroke
			(width 0.06985)
			(type default)
		)
		(layer "F.Cu")
	)
	(gr_line
		(start 30.000448 -17.134586)
		(end 30.264862 -17.399)
		(stroke
			(width 0.06985)
			(type default)
		)
		(layer "F.Cu")
	)
	(gr_line
		(start 30.000448 -16.649954)
		(end 30.000448 -17.134586)
		(stroke
			(width 0.06985)
			(type default)
		)
		(layer "F.Cu")
	)
	(gr_line
		(start 30.000448 -16.649954)
		(end 30.000702 -16.649954)
		(stroke
			(width 0.06985)
			(type default)
		)
		(layer "F.Cu")
	)
	(gr_line
		(start 30.264862 -17.399)
		(end 30.655768 -17.399)
		(stroke
			(width 0.06985)
			(type default)
		)
		(layer "F.Cu")
	)
	(gr_line
		(start 30.658308 -17.399)
		(end 30.668722 -17.399)
		(stroke
			(width 0.06985)
			(type default)
		)
		(layer "F.Cu")
	)
	(gr_line
		(start 30.744414 -6.002782)
		(end 30.999938 -5.747258)
		(stroke
			(width 0.06985)
			(type default)
		)
		(layer "F.Cu")
	)
	(gr_line
		(start 30.999938 -18.650204)
		(end 31.000192 -18.650204)
		(stroke
			(width 0.06985)
			(type default)
		)
		(layer "F.Cu")
	)
	(gr_line
		(start 30.999938 -18.650204)
		(end 31.001208 -18.648934)
		(stroke
			(width 0.06985)
			(type default)
		)
		(layer "F.Cu")
	)
	(gr_line
		(start 30.999938 -3.495548)
		(end 30.999938 -5.747258)
		(stroke
			(width 0.06985)
			(type default)
		)
		(layer "F.Cu")
	)
	(gr_line
		(start 31.001208 -17.74444)
		(end 31.001208 -18.648934)
		(stroke
			(width 0.06985)
			(type default)
		)
		(layer "F.Cu")
	)
	(gr_line
		(start 31.001208 -17.551654)
		(end 31.001208 -17.7419)
		(stroke
			(width 0.06985)
			(type default)
		)
		(layer "F.Cu")
	)
	(gr_line
		(start 33.999678 -17.134586)
		(end 34.264092 -17.399)
		(stroke
			(width 0.06985)
			(type default)
		)
		(layer "F.Cu")
	)
	(gr_line
		(start 33.999678 -16.649954)
		(end 33.999678 -17.134586)
		(stroke
			(width 0.06985)
			(type default)
		)
		(layer "F.Cu")
	)
	(gr_line
		(start 33.999678 -16.649954)
		(end 33.999932 -16.649954)
		(stroke
			(width 0.06985)
			(type default)
		)
		(layer "F.Cu")
	)
	(gr_line
		(start 33.999932 -5.747004)
		(end 34.25571 -6.002782)
		(stroke
			(width 0.06985)
			(type default)
		)
		(layer "F.Cu")
	)
	(gr_line
		(start 33.999932 -3.495548)
		(end 33.999932 -5.747004)
		(stroke
			(width 0.06985)
			(type default)
		)
		(layer "F.Cu")
	)
	(gr_line
		(start 34.264092 -17.399)
		(end 34.654998 -17.399)
		(stroke
			(width 0.06985)
			(type default)
		)
		(layer "F.Cu")
	)
	(gr_line
		(start 34.657538 -17.399)
		(end 34.667952 -17.399)
		(stroke
			(width 0.06985)
			(type default)
		)
		(layer "F.Cu")
	)
	(gr_line
		(start 34.744406 -6.002782)
		(end 34.99993 -5.747258)
		(stroke
			(width 0.06985)
			(type default)
		)
		(layer "F.Cu")
	)
	(gr_line
		(start 34.99993 -3.495548)
		(end 34.99993 -5.747258)
		(stroke
			(width 0.06985)
			(type default)
		)
		(layer "F.Cu")
	)
	(gr_line
		(start 35.000438 -18.650204)
		(end 35.000692 -18.650204)
		(stroke
			(width 0.06985)
			(type default)
		)
		(layer "F.Cu")
	)
	(gr_line
		(start 35.000438 -17.74444)
		(end 35.000438 -18.650204)
		(stroke
			(width 0.06985)
			(type default)
		)
		(layer "F.Cu")
	)
	(gr_line
		(start 35.000438 -17.551654)
		(end 35.000438 -17.7419)
		(stroke
			(width 0.06985)
			(type default)
		)
		(layer "F.Cu")
	)
	(gr_line
		(start 37.999924 -5.747004)
		(end 38.255702 -6.002782)
		(stroke
			(width 0.06985)
			(type default)
		)
		(layer "F.Cu")
	)
	(gr_line
		(start 37.999924 -3.495548)
		(end 37.999924 -5.747004)
		(stroke
			(width 0.06985)
			(type default)
		)
		(layer "F.Cu")
	)
	(gr_line
		(start 38.000178 -17.134586)
		(end 38.264592 -17.399)
		(stroke
			(width 0.06985)
			(type default)
		)
		(layer "F.Cu")
	)
	(gr_line
		(start 38.000178 -16.649954)
		(end 38.000178 -17.134586)
		(stroke
			(width 0.06985)
			(type default)
		)
		(layer "F.Cu")
	)
	(gr_line
		(start 38.000178 -16.649954)
		(end 38.000432 -16.649954)
		(stroke
			(width 0.06985)
			(type default)
		)
		(layer "F.Cu")
	)
	(gr_line
		(start 38.264592 -17.399)
		(end 38.655498 -17.399)
		(stroke
			(width 0.06985)
			(type default)
		)
		(layer "F.Cu")
	)
	(gr_line
		(start 38.658038 -17.399)
		(end 38.668452 -17.399)
		(stroke
			(width 0.06985)
			(type default)
		)
		(layer "F.Cu")
	)
	(gr_line
		(start 38.744398 -6.002782)
		(end 38.999922 -5.747258)
		(stroke
			(width 0.06985)
			(type default)
		)
		(layer "F.Cu")
	)
	(gr_line
		(start 38.999668 -18.650204)
		(end 38.999922 -18.650204)
		(stroke
			(width 0.06985)
			(type default)
		)
		(layer "F.Cu")
	)
	(gr_line
		(start 38.999668 -18.650204)
		(end 39.000938 -18.648934)
		(stroke
			(width 0.06985)
			(type default)
		)
		(layer "F.Cu")
	)
	(gr_line
		(start 38.999922 -3.495548)
		(end 38.999922 -5.747258)
		(stroke
			(width 0.06985)
			(type default)
		)
		(layer "F.Cu")
	)
	(gr_line
		(start 39.000938 -17.74444)
		(end 39.000938 -18.648934)
		(stroke
			(width 0.06985)
			(type default)
		)
		(layer "F.Cu")
	)
	(gr_line
		(start 39.000938 -17.551654)
		(end 39.000938 -17.7419)
		(stroke
			(width 0.06985)
			(type default)
		)
		(layer "F.Cu")
	)
	(gr_line
		(start 41.999408 -17.134586)
		(end 42.263822 -17.399)
		(stroke
			(width 0.06985)
			(type default)
		)
		(layer "F.Cu")
	)
	(gr_line
		(start 41.999408 -16.649954)
		(end 41.999408 -17.134586)
		(stroke
			(width 0.06985)
			(type default)
		)
		(layer "F.Cu")
	)
	(gr_line
		(start 41.999408 -16.649954)
		(end 41.999662 -16.649954)
		(stroke
			(width 0.06985)
			(type default)
		)
		(layer "F.Cu")
	)
	(gr_line
		(start 41.999916 -5.747004)
		(end 42.255694 -6.002782)
		(stroke
			(width 0.06985)
			(type default)
		)
		(layer "F.Cu")
	)
	(gr_line
		(start 41.999916 -3.495548)
		(end 41.999916 -5.747004)
		(stroke
			(width 0.06985)
			(type default)
		)
		(layer "F.Cu")
	)
	(gr_line
		(start 42.263822 -17.399)
		(end 42.654728 -17.399)
		(stroke
			(width 0.06985)
			(type default)
		)
		(layer "F.Cu")
	)
	(gr_line
		(start 42.657268 -17.399)
		(end 42.667682 -17.399)
		(stroke
			(width 0.06985)
			(type default)
		)
		(layer "F.Cu")
	)
	(gr_line
		(start 42.74439 -6.002782)
		(end 42.999914 -5.747258)
		(stroke
			(width 0.06985)
			(type default)
		)
		(layer "F.Cu")
	)
	(gr_line
		(start 42.999914 -3.495548)
		(end 42.999914 -5.747258)
		(stroke
			(width 0.06985)
			(type default)
		)
		(layer "F.Cu")
	)
	(gr_line
		(start 43.000168 -18.650204)
		(end 43.000422 -18.650204)
		(stroke
			(width 0.06985)
			(type default)
		)
		(layer "F.Cu")
	)
	(gr_line
		(start 43.000168 -17.74444)
		(end 43.000168 -18.650204)
		(stroke
			(width 0.06985)
			(type default)
		)
		(layer "F.Cu")
	)
	(gr_line
		(start 43.000168 -17.551654)
		(end 43.000168 -17.7419)
		(stroke
			(width 0.06985)
			(type default)
		)
		(layer "F.Cu")
	)
	(gr_line
		(start 53.999638 -17.123156)
		(end 54.290722 -17.41424)
		(stroke
			(width 0.06985)
			(type default)
		)
		(layer "F.Cu")
	)
	(gr_line
		(start 53.999638 -16.649954)
		(end 53.999638 -17.123156)
		(stroke
			(width 0.06985)
			(type default)
		)
		(layer "F.Cu")
	)
	(gr_line
		(start 53.999638 -16.649954)
		(end 53.999892 -16.649954)
		(stroke
			(width 0.06985)
			(type default)
		)
		(layer "F.Cu")
	)
	(gr_line
		(start 53.999892 -5.747004)
		(end 54.25567 -6.002782)
		(stroke
			(width 0.06985)
			(type default)
		)
		(layer "F.Cu")
	)
	(gr_line
		(start 53.999892 -3.495548)
		(end 53.999892 -5.747004)
		(stroke
			(width 0.06985)
			(type default)
		)
		(layer "F.Cu")
	)
	(gr_line
		(start 54.290722 -17.41424)
		(end 54.652672 -17.41424)
		(stroke
			(width 0.06985)
			(type default)
		)
		(layer "F.Cu")
	)
	(gr_line
		(start 54.744366 -6.002782)
		(end 54.99989 -5.747258)
		(stroke
			(width 0.06985)
			(type default)
		)
		(layer "F.Cu")
	)
	(gr_line
		(start 54.99989 -3.495548)
		(end 54.99989 -5.747258)
		(stroke
			(width 0.06985)
			(type default)
		)
		(layer "F.Cu")
	)
	(gr_line
		(start 55.000398 -18.650204)
		(end 55.000652 -18.650204)
		(stroke
			(width 0.06985)
			(type default)
		)
		(layer "F.Cu")
	)
	(gr_line
		(start 55.000398 -17.554956)
		(end 55.000398 -18.650204)
		(stroke
			(width 0.06985)
			(type default)
		)
		(layer "F.Cu")
	)
	(gr_line
		(start 57.999884 -5.747004)
		(end 58.255662 -6.002782)
		(stroke
			(width 0.06985)
			(type default)
		)
		(layer "F.Cu")
	)
	(gr_line
		(start 57.999884 -3.495548)
		(end 57.999884 -5.747004)
		(stroke
			(width 0.06985)
			(type default)
		)
		(layer "F.Cu")
	)
	(gr_line
		(start 58.000138 -17.134586)
		(end 58.264552 -17.399)
		(stroke
			(width 0.06985)
			(type default)
		)
		(layer "F.Cu")
	)
	(gr_line
		(start 58.000138 -16.649954)
		(end 58.000138 -17.134586)
		(stroke
			(width 0.06985)
			(type default)
		)
		(layer "F.Cu")
	)
	(gr_line
		(start 58.000138 -16.649954)
		(end 58.000392 -16.649954)
		(stroke
			(width 0.06985)
			(type default)
		)
		(layer "F.Cu")
	)
	(gr_line
		(start 58.264552 -17.399)
		(end 58.654188 -17.399)
		(stroke
			(width 0.06985)
			(type default)
		)
		(layer "F.Cu")
	)
	(gr_line
		(start 58.656728 -17.399)
		(end 58.668412 -17.399)
		(stroke
			(width 0.06985)
			(type default)
		)
		(layer "F.Cu")
	)
	(gr_line
		(start 58.744358 -6.002782)
		(end 58.999882 -5.747258)
		(stroke
			(width 0.06985)
			(type default)
		)
		(layer "F.Cu")
	)
	(gr_line
		(start 58.999628 -18.650204)
		(end 58.999882 -18.650204)
		(stroke
			(width 0.06985)
			(type default)
		)
		(layer "F.Cu")
	)
	(gr_line
		(start 58.999628 -17.74444)
		(end 58.999628 -18.650204)
		(stroke
			(width 0.06985)
			(type default)
		)
		(layer "F.Cu")
	)
	(gr_line
		(start 58.999628 -17.552924)
		(end 58.999628 -17.7419)
		(stroke
			(width 0.06985)
			(type default)
		)
		(layer "F.Cu")
	)
	(gr_line
		(start 58.999882 -3.495548)
		(end 58.999882 -5.747258)
		(stroke
			(width 0.06985)
			(type default)
		)
		(layer "F.Cu")
	)
	(gr_line
		(start 61.999368 -17.134586)
		(end 62.263782 -17.399)
		(stroke
			(width 0.06985)
			(type default)
		)
		(layer "F.Cu")
	)
	(gr_line
		(start 61.999368 -16.649954)
		(end 61.999368 -17.134586)
		(stroke
			(width 0.06985)
			(type default)
		)
		(layer "F.Cu")
	)
	(gr_line
		(start 61.999368 -16.649954)
		(end 61.999622 -16.649954)
		(stroke
			(width 0.06985)
			(type default)
		)
		(layer "F.Cu")
	)
	(gr_line
		(start 61.999876 -5.747004)
		(end 62.255654 -6.002782)
		(stroke
			(width 0.06985)
			(type default)
		)
		(layer "F.Cu")
	)
	(gr_line
		(start 61.999876 -3.495548)
		(end 61.999876 -5.747004)
		(stroke
			(width 0.06985)
			(type default)
		)
		(layer "F.Cu")
	)
	(gr_line
		(start 62.263782 -17.399)
		(end 62.654688 -17.399)
		(stroke
			(width 0.06985)
			(type default)
		)
		(layer "F.Cu")
	)
	(gr_line
		(start 62.657228 -17.399)
		(end 62.667642 -17.399)
		(stroke
			(width 0.06985)
			(type default)
		)
		(layer "F.Cu")
	)
	(gr_line
		(start 62.74435 -6.002782)
		(end 62.999874 -5.747258)
		(stroke
			(width 0.06985)
			(type default)
		)
		(layer "F.Cu")
	)
	(gr_line
		(start 62.84976 -17.208754)
		(end 62.84976 -17.216882)
		(stroke
			(width 0.06985)
			(type default)
		)
		(layer "F.Cu")
	)
	(gr_line
		(start 62.999874 -3.495548)
		(end 62.999874 -5.747258)
		(stroke
			(width 0.06985)
			(type default)
		)
		(layer "F.Cu")
	)
	(gr_line
		(start 63.000128 -18.650204)
		(end 63.000382 -18.650204)
		(stroke
			(width 0.06985)
			(type default)
		)
		(layer "F.Cu")
	)
	(gr_line
		(start 63.000128 -17.74444)
		(end 63.000128 -18.650204)
		(stroke
			(width 0.06985)
			(type default)
		)
		(layer "F.Cu")
	)
	(gr_line
		(start 63.000128 -17.551654)
		(end 63.000128 -17.7419)
		(stroke
			(width 0.06985)
			(type default)
		)
		(layer "F.Cu")
	)
	(gr_line
		(start 65.999868 -17.353026)
		(end 66.210942 -17.5641)
		(stroke
			(width 0.06985)
			(type default)
		)
		(layer "F.Cu")
	)
	(gr_line
		(start 65.999868 -16.649954)
		(end 65.999868 -17.353026)
		(stroke
			(width 0.06985)
			(type default)
		)
		(layer "F.Cu")
	)
	(gr_line
		(start 65.999868 -16.649954)
		(end 66.000122 -16.649954)
		(stroke
			(width 0.06985)
			(type default)
		)
		(layer "F.Cu")
	)
	(gr_line
		(start 65.999868 -5.829808)
		(end 66.214244 -6.044184)
		(stroke
			(width 0.06985)
			(type default)
		)
		(layer "F.Cu")
	)
	(gr_line
		(start 65.999868 -3.495548)
		(end 65.999868 -5.829808)
		(stroke
			(width 0.06985)
			(type default)
		)
		(layer "F.Cu")
	)
	(gr_line
		(start 66.210942 -17.5641)
		(end 66.6242 -17.5641)
		(stroke
			(width 0.06985)
			(type default)
		)
		(layer "F.Cu")
	)
	(gr_line
		(start 66.6623 -18.313146)
		(end 66.999358 -18.650204)
		(stroke
			(width 0.06985)
			(type default)
		)
		(layer "F.Cu")
	)
	(gr_line
		(start 66.6623 -18.014442)
		(end 66.6623 -18.313146)
		(stroke
			(width 0.06985)
			(type default)
		)
		(layer "F.Cu")
	)
	(gr_line
		(start 66.702686 -6.044184)
		(end 66.999866 -5.747004)
		(stroke
			(width 0.06985)
			(type default)
		)
		(layer "F.Cu")
	)
	(gr_line
		(start 66.999358 -18.650204)
		(end 66.999612 -18.650204)
		(stroke
			(width 0.06985)
			(type default)
		)
		(layer "F.Cu")
	)
	(gr_line
		(start 66.999866 -3.495548)
		(end 66.999866 -5.747004)
		(stroke
			(width 0.06985)
			(type default)
		)
		(layer "F.Cu")
	)
	(gr_line
		(start 69.99986 -5.747258)
		(end 70.255384 -6.002782)
		(stroke
			(width 0.06985)
			(type default)
		)
		(layer "F.Cu")
	)
	(gr_line
		(start 69.99986 -3.495548)
		(end 69.99986 -5.747258)
		(stroke
			(width 0.06985)
			(type default)
		)
		(layer "F.Cu")
	)
	(gr_line
		(start 70.000368 -17.223486)
		(end 70.325742 -17.54886)
		(stroke
			(width 0.06985)
			(type default)
		)
		(layer "F.Cu")
	)
	(gr_line
		(start 70.000368 -16.649954)
		(end 70.000368 -17.223486)
		(stroke
			(width 0.06985)
			(type default)
		)
		(layer "F.Cu")
	)
	(gr_line
		(start 70.000368 -16.649954)
		(end 70.000622 -16.649954)
		(stroke
			(width 0.06985)
			(type default)
		)
		(layer "F.Cu")
	)
	(gr_line
		(start 70.325742 -17.54886)
		(end 70.64756 -17.54886)
		(stroke
			(width 0.06985)
			(type default)
		)
		(layer "F.Cu")
	)
	(gr_line
		(start 70.673722 -18.324068)
		(end 70.999858 -18.650204)
		(stroke
			(width 0.06985)
			(type default)
		)
		(layer "F.Cu")
	)
	(gr_line
		(start 70.673722 -18.01114)
		(end 70.673722 -18.324068)
		(stroke
			(width 0.06985)
			(type default)
		)
		(layer "F.Cu")
	)
	(gr_line
		(start 70.74408 -6.002782)
		(end 70.999858 -5.747004)
		(stroke
			(width 0.06985)
			(type default)
		)
		(layer "F.Cu")
	)
	(gr_line
		(start 70.999858 -18.650204)
		(end 71.000112 -18.650204)
		(stroke
			(width 0.06985)
			(type default)
		)
		(layer "F.Cu")
	)
	(gr_line
		(start 70.999858 -3.495548)
		(end 70.999858 -5.747004)
		(stroke
			(width 0.06985)
			(type default)
		)
		(layer "F.Cu")
	)
	(gr_line
		(start 73.999598 -16.649954)
		(end 73.999852 -16.649954)
		(stroke
			(width 0.06985)
			(type default)
		)
		(layer "F.Cu")
	)
	(gr_line
		(start 73.999598 -16.649954)
		(end 74.748644 -17.399)
		(stroke
			(width 0.06985)
			(type default)
		)
		(layer "F.Cu")
	)
	(gr_line
		(start 73.999852 -5.747004)
		(end 74.25563 -6.002782)
		(stroke
			(width 0.06985)
			(type default)
		)
		(layer "F.Cu")
	)
	(gr_line
		(start 73.999852 -3.495548)
		(end 73.999852 -5.747004)
		(stroke
			(width 0.06985)
			(type default)
		)
		(layer "F.Cu")
	)
	(gr_line
		(start 74.744326 -6.002782)
		(end 74.99985 -5.747258)
		(stroke
			(width 0.06985)
			(type default)
		)
		(layer "F.Cu")
	)
	(gr_line
		(start 74.748644 -17.399)
		(end 74.973942 -17.399)
		(stroke
			(width 0.06985)
			(type default)
		)
		(layer "F.Cu")
	)
	(gr_line
		(start 74.99985 -3.495548)
		(end 74.99985 -5.747258)
		(stroke
			(width 0.06985)
			(type default)
		)
		(layer "F.Cu")
	)
	(gr_line
		(start 75.000358 -18.650204)
		(end 75.000612 -18.650204)
		(stroke
			(width 0.06985)
			(type default)
		)
		(layer "F.Cu")
	)
	(gr_line
		(start 75.000358 -18.060924)
		(end 75.000358 -18.650204)
		(stroke
			(width 0.06985)
			(type default)
		)
		(layer "F.Cu")
	)
	(gr_line
		(start 75.000358 -18.060924)
		(end 75.316842 -17.74444)
		(stroke
			(width 0.06985)
			(type default)
		)
		(layer "F.Cu")
	)
	(gr_line
		(start 7.999984 -5.747258)
		(end 8.255508 -6.002782)
		(stroke
			(width 0.06985)
			(type default)
		)
		(layer "B.Cu")
	)
	(gr_line
		(start 7.999984 -3.114548)
		(end 7.999984 -5.747258)
		(stroke
			(width 0.06985)
			(type default)
		)
		(layer "B.Cu")
	)
	(gr_line
		(start 8.000238 -23.149814)
		(end 8.000492 -23.149814)
		(stroke
			(width 0.06985)
			(type default)
		)
		(layer "B.Cu")
	)
	(gr_line
		(start 8.000238 -23.149814)
		(end 8.187182 -22.96287)
		(stroke
			(width 0.06985)
			(type default)
		)
		(layer "B.Cu")
	)
	(gr_line
		(start 8.187182 -22.34184)
		(end 8.187182 -22.96287)
		(stroke
			(width 0.06985)
			(type default)
		)
		(layer "B.Cu")
	)
	(gr_line
		(start 8.187182 -22.1996)
		(end 8.187182 -22.3393)
		(stroke
			(width 0.06985)
			(type default)
		)
		(layer "B.Cu")
	)
	(gr_line
		(start 8.469122 -21.9964)
		(end 8.530082 -21.9964)
		(stroke
			(width 0.06985)
			(type default)
		)
		(layer "B.Cu")
	)
	(gr_line
		(start 8.532622 -21.9964)
		(end 8.796782 -21.9964)
		(stroke
			(width 0.06985)
			(type default)
		)
		(layer "B.Cu")
	)
	(gr_line
		(start 8.744204 -6.002782)
		(end 8.999982 -5.747004)
		(stroke
			(width 0.06985)
			(type default)
		)
		(layer "B.Cu")
	)
	(gr_line
		(start 8.796782 -21.9964)
		(end 8.999728 -21.793454)
		(stroke
			(width 0.06985)
			(type default)
		)
		(layer "B.Cu")
	)
	(gr_line
		(start 8.999728 -21.149564)
		(end 8.999728 -21.793454)
		(stroke
			(width 0.06985)
			(type default)
		)
		(layer "B.Cu")
	)
	(gr_line
		(start 8.999728 -21.149564)
		(end 8.999982 -21.149564)
		(stroke
			(width 0.06985)
			(type default)
		)
		(layer "B.Cu")
	)
	(gr_line
		(start 8.999982 -3.114548)
		(end 8.999982 -5.747004)
		(stroke
			(width 0.06985)
			(type default)
		)
		(layer "B.Cu")
	)
	(gr_line
		(start 11.999722 -23.149814)
		(end 12.000738 -23.149814)
		(stroke
			(width 0.06985)
			(type default)
		)
		(layer "B.Cu")
	)
	(gr_line
		(start 11.999976 -5.747004)
		(end 12.255754 -6.002782)
		(stroke
			(width 0.06985)
			(type default)
		)
		(layer "B.Cu")
	)
	(gr_line
		(start 11.999976 -3.114548)
		(end 11.999976 -5.747004)
		(stroke
			(width 0.06985)
			(type default)
		)
		(layer "B.Cu")
	)
	(gr_line
		(start 12.000738 -23.149814)
		(end 12.187682 -22.96287)
		(stroke
			(width 0.06985)
			(type default)
		)
		(layer "B.Cu")
	)
	(gr_line
		(start 12.187682 -22.34184)
		(end 12.187682 -22.96287)
		(stroke
			(width 0.06985)
			(type default)
		)
		(layer "B.Cu")
	)
	(gr_line
		(start 12.187682 -22.1996)
		(end 12.187682 -22.3393)
		(stroke
			(width 0.06985)
			(type default)
		)
		(layer "B.Cu")
	)
	(gr_line
		(start 12.469622 -21.9964)
		(end 12.530582 -21.9964)
		(stroke
			(width 0.06985)
			(type default)
		)
		(layer "B.Cu")
	)
	(gr_line
		(start 12.533122 -21.9964)
		(end 12.797282 -21.9964)
		(stroke
			(width 0.06985)
			(type default)
		)
		(layer "B.Cu")
	)
	(gr_line
		(start 12.74445 -6.002782)
		(end 12.999974 -5.747258)
		(stroke
			(width 0.06985)
			(type default)
		)
		(layer "B.Cu")
	)
	(gr_line
		(start 12.797282 -21.9964)
		(end 13.000228 -21.793454)
		(stroke
			(width 0.06985)
			(type default)
		)
		(layer "B.Cu")
	)
	(gr_line
		(start 12.999974 -3.114548)
		(end 12.999974 -5.747258)
		(stroke
			(width 0.06985)
			(type default)
		)
		(layer "B.Cu")
	)
	(gr_line
		(start 13.000228 -21.149564)
		(end 13.000228 -21.793454)
		(stroke
			(width 0.06985)
			(type default)
		)
		(layer "B.Cu")
	)
	(gr_line
		(start 13.000228 -21.149564)
		(end 13.000482 -21.149564)
		(stroke
			(width 0.06985)
			(type default)
		)
		(layer "B.Cu")
	)
	(gr_line
		(start 15.999968 -5.747004)
		(end 16.255746 -6.002782)
		(stroke
			(width 0.06985)
			(type default)
		)
		(layer "B.Cu")
	)
	(gr_line
		(start 15.999968 -3.114548)
		(end 15.999968 -5.747004)
		(stroke
			(width 0.06985)
			(type default)
		)
		(layer "B.Cu")
	)
	(gr_line
		(start 16.000222 -23.14956)
		(end 16.000222 -23.149814)
		(stroke
			(width 0.06985)
			(type default)
		)
		(layer "B.Cu")
	)
	(gr_line
		(start 16.000222 -23.14956)
		(end 16.186912 -22.96287)
		(stroke
			(width 0.06985)
			(type default)
		)
		(layer "B.Cu")
	)
	(gr_line
		(start 16.186912 -22.34184)
		(end 16.186912 -22.96287)
		(stroke
			(width 0.06985)
			(type default)
		)
		(layer "B.Cu")
	)
	(gr_line
		(start 16.186912 -22.1996)
		(end 16.186912 -22.3393)
		(stroke
			(width 0.06985)
			(type default)
		)
		(layer "B.Cu")
	)
	(gr_line
		(start 16.468852 -21.9964)
		(end 16.529812 -21.9964)
		(stroke
			(width 0.06985)
			(type default)
		)
		(layer "B.Cu")
	)
	(gr_line
		(start 16.532352 -21.9964)
		(end 16.796512 -21.9964)
		(stroke
			(width 0.06985)
			(type default)
		)
		(layer "B.Cu")
	)
	(gr_line
		(start 16.744442 -6.002782)
		(end 16.999966 -5.747258)
		(stroke
			(width 0.06985)
			(type default)
		)
		(layer "B.Cu")
	)
	(gr_line
		(start 16.796512 -21.9964)
		(end 16.999458 -21.793454)
		(stroke
			(width 0.06985)
			(type default)
		)
		(layer "B.Cu")
	)
	(gr_line
		(start 16.999458 -21.149564)
		(end 16.999458 -21.793454)
		(stroke
			(width 0.06985)
			(type default)
		)
		(layer "B.Cu")
	)
	(gr_line
		(start 16.999458 -21.149564)
		(end 16.999712 -21.149564)
		(stroke
			(width 0.06985)
			(type default)
		)
		(layer "B.Cu")
	)
	(gr_line
		(start 16.999966 -3.114548)
		(end 16.999966 -5.747258)
		(stroke
			(width 0.06985)
			(type default)
		)
		(layer "B.Cu")
	)
	(gr_line
		(start 19.99996 -5.747004)
		(end 20.255738 -6.002782)
		(stroke
			(width 0.06985)
			(type default)
		)
		(layer "B.Cu")
	)
	(gr_line
		(start 19.99996 -3.114548)
		(end 19.99996 -5.747004)
		(stroke
			(width 0.06985)
			(type default)
		)
		(layer "B.Cu")
	)
	(gr_line
		(start 20.000722 -23.149814)
		(end 20.186142 -22.964394)
		(stroke
			(width 0.06985)
			(type default)
		)
		(layer "B.Cu")
	)
	(gr_line
		(start 20.186142 -22.34184)
		(end 20.186142 -22.964394)
		(stroke
			(width 0.06985)
			(type default)
		)
		(layer "B.Cu")
	)
	(gr_line
		(start 20.186142 -22.1996)
		(end 20.186142 -22.3393)
		(stroke
			(width 0.06985)
			(type default)
		)
		(layer "B.Cu")
	)
	(gr_line
		(start 20.468082 -21.9964)
		(end 20.529042 -21.9964)
		(stroke
			(width 0.06985)
			(type default)
		)
		(layer "B.Cu")
	)
	(gr_line
		(start 20.531582 -21.9964)
		(end 20.795742 -21.9964)
		(stroke
			(width 0.06985)
			(type default)
		)
		(layer "B.Cu")
	)
	(gr_line
		(start 20.744434 -6.002782)
		(end 20.999958 -5.747258)
		(stroke
			(width 0.06985)
			(type default)
		)
		(layer "B.Cu")
	)
	(gr_line
		(start 20.795742 -21.9964)
		(end 20.998688 -21.793454)
		(stroke
			(width 0.06985)
			(type default)
		)
		(layer "B.Cu")
	)
	(gr_line
		(start 20.998688 -21.149564)
		(end 20.998688 -21.793454)
		(stroke
			(width 0.06985)
			(type default)
		)
		(layer "B.Cu")
	)
	(gr_line
		(start 20.998688 -21.149564)
		(end 21.000212 -21.149564)
		(stroke
			(width 0.06985)
			(type default)
		)
		(layer "B.Cu")
	)
	(gr_line
		(start 20.999958 -3.114548)
		(end 20.999958 -5.747258)
		(stroke
			(width 0.06985)
			(type default)
		)
		(layer "B.Cu")
	)
	(gr_line
		(start 23.998428 -23.149814)
		(end 23.999952 -23.149814)
		(stroke
			(width 0.06985)
			(type default)
		)
		(layer "B.Cu")
	)
	(gr_line
		(start 23.998428 -23.149814)
		(end 24.185372 -22.96287)
		(stroke
			(width 0.06985)
			(type default)
		)
		(layer "B.Cu")
	)
	(gr_line
		(start 23.999952 -5.747004)
		(end 24.25573 -6.002782)
		(stroke
			(width 0.06985)
			(type default)
		)
		(layer "B.Cu")
	)
	(gr_line
		(start 23.999952 -3.114548)
		(end 23.999952 -5.747004)
		(stroke
			(width 0.06985)
			(type default)
		)
		(layer "B.Cu")
	)
	(gr_line
		(start 24.185372 -22.34184)
		(end 24.185372 -22.96287)
		(stroke
			(width 0.06985)
			(type default)
		)
		(layer "B.Cu")
	)
	(gr_line
		(start 24.185372 -22.1996)
		(end 24.185372 -22.3393)
		(stroke
			(width 0.06985)
			(type default)
		)
		(layer "B.Cu")
	)
	(gr_line
		(start 24.467312 -21.9964)
		(end 24.528272 -21.9964)
		(stroke
			(width 0.06985)
			(type default)
		)
		(layer "B.Cu")
	)
	(gr_line
		(start 24.530812 -21.9964)
		(end 24.794972 -21.9964)
		(stroke
			(width 0.06985)
			(type default)
		)
		(layer "B.Cu")
	)
	(gr_line
		(start 24.744426 -6.002782)
		(end 24.99995 -5.747258)
		(stroke
			(width 0.06985)
			(type default)
		)
		(layer "B.Cu")
	)
	(gr_line
		(start 24.794972 -21.9964)
		(end 24.997918 -21.793454)
		(stroke
			(width 0.06985)
			(type default)
		)
		(layer "B.Cu")
	)
	(gr_line
		(start 24.997918 -21.149564)
		(end 24.997918 -21.793454)
		(stroke
			(width 0.06985)
			(type default)
		)
		(layer "B.Cu")
	)
	(gr_line
		(start 24.997918 -21.149564)
		(end 25.000712 -21.149564)
		(stroke
			(width 0.06985)
			(type default)
		)
		(layer "B.Cu")
	)
	(gr_line
		(start 24.99995 -3.114548)
		(end 24.99995 -5.747258)
		(stroke
			(width 0.06985)
			(type default)
		)
		(layer "B.Cu")
	)
	(gr_line
		(start 27.997658 -23.149814)
		(end 28.000452 -23.149814)
		(stroke
			(width 0.06985)
			(type default)
		)
		(layer "B.Cu")
	)
	(gr_line
		(start 27.997658 -23.149814)
		(end 28.184602 -22.96287)
		(stroke
			(width 0.06985)
			(type default)
		)
		(layer "B.Cu")
	)
	(gr_line
		(start 27.999944 -5.747004)
		(end 28.255722 -6.002782)
		(stroke
			(width 0.06985)
			(type default)
		)
		(layer "B.Cu")
	)
	(gr_line
		(start 27.999944 -3.114548)
		(end 27.999944 -5.747004)
		(stroke
			(width 0.06985)
			(type default)
		)
		(layer "B.Cu")
	)
	(gr_line
		(start 28.184602 -22.34184)
		(end 28.184602 -22.96287)
		(stroke
			(width 0.06985)
			(type default)
		)
		(layer "B.Cu")
	)
	(gr_line
		(start 28.184602 -22.1996)
		(end 28.184602 -22.3393)
		(stroke
			(width 0.06985)
			(type default)
		)
		(layer "B.Cu")
	)
	(gr_line
		(start 28.466542 -21.9964)
		(end 28.527502 -21.9964)
		(stroke
			(width 0.06985)
			(type default)
		)
		(layer "B.Cu")
	)
	(gr_line
		(start 28.530042 -21.9964)
		(end 28.794202 -21.9964)
		(stroke
			(width 0.06985)
			(type default)
		)
		(layer "B.Cu")
	)
	(gr_line
		(start 28.744418 -6.002782)
		(end 28.999942 -5.747258)
		(stroke
			(width 0.06985)
			(type default)
		)
		(layer "B.Cu")
	)
	(gr_line
		(start 28.794202 -21.9964)
		(end 28.997148 -21.793454)
		(stroke
			(width 0.06985)
			(type default)
		)
		(layer "B.Cu")
	)
	(gr_line
		(start 28.997148 -21.149564)
		(end 28.997148 -21.793454)
		(stroke
			(width 0.06985)
			(type default)
		)
		(layer "B.Cu")
	)
	(gr_line
		(start 28.997148 -21.149564)
		(end 28.999942 -21.149564)
		(stroke
			(width 0.06985)
			(type default)
		)
		(layer "B.Cu")
	)
	(gr_line
		(start 28.999942 -3.114548)
		(end 28.999942 -5.747258)
		(stroke
			(width 0.06985)
			(type default)
		)
		(layer "B.Cu")
	)
	(gr_line
		(start 31.996888 -23.149814)
		(end 31.999682 -23.149814)
		(stroke
			(width 0.06985)
			(type default)
		)
		(layer "B.Cu")
	)
	(gr_line
		(start 31.996888 -23.149814)
		(end 32.183832 -22.96287)
		(stroke
			(width 0.06985)
			(type default)
		)
		(layer "B.Cu")
	)
	(gr_line
		(start 31.999936 -5.747004)
		(end 32.255714 -6.002782)
		(stroke
			(width 0.06985)
			(type default)
		)
		(layer "B.Cu")
	)
	(gr_line
		(start 31.999936 -3.114548)
		(end 31.999936 -5.747004)
		(stroke
			(width 0.06985)
			(type default)
		)
		(layer "B.Cu")
	)
	(gr_line
		(start 32.183832 -22.34184)
		(end 32.183832 -22.96287)
		(stroke
			(width 0.06985)
			(type default)
		)
		(layer "B.Cu")
	)
	(gr_line
		(start 32.183832 -22.1996)
		(end 32.183832 -22.3393)
		(stroke
			(width 0.06985)
			(type default)
		)
		(layer "B.Cu")
	)
	(gr_line
		(start 32.465772 -21.9964)
		(end 32.526732 -21.9964)
		(stroke
			(width 0.06985)
			(type default)
		)
		(layer "B.Cu")
	)
	(gr_line
		(start 32.529272 -21.9964)
		(end 32.793432 -21.9964)
		(stroke
			(width 0.06985)
			(type default)
		)
		(layer "B.Cu")
	)
	(gr_line
		(start 32.74441 -6.002782)
		(end 32.999934 -5.747258)
		(stroke
			(width 0.06985)
			(type default)
		)
		(layer "B.Cu")
	)
	(gr_line
		(start 32.793432 -21.9964)
		(end 32.996378 -21.793454)
		(stroke
			(width 0.06985)
			(type default)
		)
		(layer "B.Cu")
	)
	(gr_line
		(start 32.996378 -21.149564)
		(end 32.996378 -21.793454)
		(stroke
			(width 0.06985)
			(type default)
		)
		(layer "B.Cu")
	)
	(gr_line
		(start 32.996378 -21.149564)
		(end 33.000442 -21.149564)
		(stroke
			(width 0.06985)
			(type default)
		)
		(layer "B.Cu")
	)
	(gr_line
		(start 32.999934 -3.114548)
		(end 32.999934 -5.747258)
		(stroke
			(width 0.06985)
			(type default)
		)
		(layer "B.Cu")
	)
	(gr_line
		(start 35.999928 -5.747004)
		(end 36.255706 -6.002782)
		(stroke
			(width 0.06985)
			(type default)
		)
		(layer "B.Cu")
	)
	(gr_line
		(start 35.999928 -3.114548)
		(end 35.999928 -5.747004)
		(stroke
			(width 0.06985)
			(type default)
		)
		(layer "B.Cu")
	)
	(gr_line
		(start 36.000182 -23.149814)
		(end 36.183062 -22.966934)
		(stroke
			(width 0.06985)
			(type default)
		)
		(layer "B.Cu")
	)
	(gr_line
		(start 36.183062 -22.34184)
		(end 36.183062 -22.966934)
		(stroke
			(width 0.06985)
			(type default)
		)
		(layer "B.Cu")
	)
	(gr_line
		(start 36.183062 -22.1996)
		(end 36.183062 -22.3393)
		(stroke
			(width 0.06985)
			(type default)
		)
		(layer "B.Cu")
	)
	(gr_line
		(start 36.465002 -21.9964)
		(end 36.525962 -21.9964)
		(stroke
			(width 0.06985)
			(type default)
		)
		(layer "B.Cu")
	)
	(gr_line
		(start 36.528502 -21.9964)
		(end 36.792662 -21.9964)
		(stroke
			(width 0.06985)
			(type default)
		)
		(layer "B.Cu")
	)
	(gr_line
		(start 36.744402 -6.002782)
		(end 36.999926 -5.747258)
		(stroke
			(width 0.06985)
			(type default)
		)
		(layer "B.Cu")
	)
	(gr_line
		(start 36.792662 -21.9964)
		(end 36.995608 -21.793454)
		(stroke
			(width 0.06985)
			(type default)
		)
		(layer "B.Cu")
	)
	(gr_line
		(start 36.995608 -21.149564)
		(end 36.995608 -21.793454)
		(stroke
			(width 0.06985)
			(type default)
		)
		(layer "B.Cu")
	)
	(gr_line
		(start 36.995608 -21.149564)
		(end 36.999672 -21.149564)
		(stroke
			(width 0.06985)
			(type default)
		)
		(layer "B.Cu")
	)
	(gr_line
		(start 36.999926 -3.114548)
		(end 36.999926 -5.747258)
		(stroke
			(width 0.06985)
			(type default)
		)
		(layer "B.Cu")
	)
	(gr_line
		(start 39.99992 -5.828538)
		(end 40.200834 -6.029452)
		(stroke
			(width 0.06985)
			(type default)
		)
		(layer "B.Cu")
	)
	(gr_line
		(start 39.99992 -3.990848)
		(end 39.99992 -5.828538)
		(stroke
			(width 0.06985)
			(type default)
		)
		(layer "B.Cu")
	)
	(gr_line
		(start 40.000682 -23.14956)
		(end 40.000682 -23.149814)
		(stroke
			(width 0.06985)
			(type default)
		)
		(layer "B.Cu")
	)
	(gr_line
		(start 40.000682 -23.14956)
		(end 40.503602 -22.64664)
		(stroke
			(width 0.06985)
			(type default)
		)
		(layer "B.Cu")
	)
	(gr_line
		(start 40.39616 -22.178518)
		(end 40.503602 -22.28596)
		(stroke
			(width 0.06985)
			(type default)
		)
		(layer "B.Cu")
	)
	(gr_line
		(start 40.397684 -21.6916)
		(end 40.622982 -21.6916)
		(stroke
			(width 0.06985)
			(type default)
		)
		(layer "B.Cu")
	)
	(gr_line
		(start 40.503602 -22.28596)
		(end 40.503602 -22.64664)
		(stroke
			(width 0.06985)
			(type default)
		)
		(layer "B.Cu")
	)
	(gr_line
		(start 40.622982 -21.6916)
		(end 40.994838 -21.319744)
		(stroke
			(width 0.06985)
			(type default)
		)
		(layer "B.Cu")
	)
	(gr_line
		(start 40.68953 -6.029452)
		(end 40.999918 -5.719064)
		(stroke
			(width 0.06985)
			(type default)
		)
		(layer "B.Cu")
	)
	(gr_line
		(start 40.994838 -21.154644)
		(end 40.994838 -21.319744)
		(stroke
			(width 0.06985)
			(type default)
		)
		(layer "B.Cu")
	)
	(gr_line
		(start 40.994838 -21.154644)
		(end 40.999918 -21.149564)
		(stroke
			(width 0.06985)
			(type default)
		)
		(layer "B.Cu")
	)
	(gr_line
		(start 40.999918 -21.149564)
		(end 41.000172 -21.149564)
		(stroke
			(width 0.06985)
			(type default)
		)
		(layer "B.Cu")
	)
	(gr_line
		(start 40.999918 -3.114548)
		(end 40.999918 -5.719064)
		(stroke
			(width 0.06985)
			(type default)
		)
		(layer "B.Cu")
	)
	(gr_line
		(start 51.999642 -23.149814)
		(end 52.179982 -22.969474)
		(stroke
			(width 0.06985)
			(type default)
		)
		(layer "B.Cu")
	)
	(gr_line
		(start 51.999896 -5.747004)
		(end 52.255674 -6.002782)
		(stroke
			(width 0.06985)
			(type default)
		)
		(layer "B.Cu")
	)
	(gr_line
		(start 51.999896 -3.114548)
		(end 51.999896 -5.747004)
		(stroke
			(width 0.06985)
			(type default)
		)
		(layer "B.Cu")
	)
	(gr_line
		(start 52.179982 -22.34184)
		(end 52.179982 -22.969474)
		(stroke
			(width 0.06985)
			(type default)
		)
		(layer "B.Cu")
	)
	(gr_line
		(start 52.179982 -22.1996)
		(end 52.179982 -22.3393)
		(stroke
			(width 0.06985)
			(type default)
		)
		(layer "B.Cu")
	)
	(gr_line
		(start 52.461922 -21.9964)
		(end 52.522882 -21.9964)
		(stroke
			(width 0.06985)
			(type default)
		)
		(layer "B.Cu")
	)
	(gr_line
		(start 52.525422 -21.9964)
		(end 52.789582 -21.9964)
		(stroke
			(width 0.06985)
			(type default)
		)
		(layer "B.Cu")
	)
	(gr_line
		(start 52.74437 -6.002782)
		(end 52.999894 -5.747258)
		(stroke
			(width 0.06985)
			(type default)
		)
		(layer "B.Cu")
	)
	(gr_line
		(start 52.789582 -21.9964)
		(end 52.992528 -21.793454)
		(stroke
			(width 0.06985)
			(type default)
		)
		(layer "B.Cu")
	)
	(gr_line
		(start 52.992528 -21.149564)
		(end 52.992528 -21.793454)
		(stroke
			(width 0.06985)
			(type default)
		)
		(layer "B.Cu")
	)
	(gr_line
		(start 52.992528 -21.149564)
		(end 53.000402 -21.149564)
		(stroke
			(width 0.06985)
			(type default)
		)
		(layer "B.Cu")
	)
	(gr_line
		(start 52.999894 -3.114548)
		(end 52.999894 -5.747258)
		(stroke
			(width 0.06985)
			(type default)
		)
		(layer "B.Cu")
	)
	(gr_line
		(start 55.992268 -23.142194)
		(end 55.999634 -23.14956)
		(stroke
			(width 0.06985)
			(type default)
		)
		(layer "B.Cu")
	)
	(gr_line
		(start 55.992268 -22.41677)
		(end 55.992268 -23.142194)
		(stroke
			(width 0.06985)
			(type default)
		)
		(layer "B.Cu")
	)
	(gr_line
		(start 55.992268 -22.331426)
		(end 55.992268 -22.41423)
		(stroke
			(width 0.06985)
			(type default)
		)
		(layer "B.Cu")
	)
	(gr_line
		(start 55.999634 -23.14956)
		(end 56.000142 -23.149814)
		(stroke
			(width 0.06985)
			(type default)
		)
		(layer "B.Cu")
	)
	(gr_line
		(start 55.999888 -5.699506)
		(end 56.279034 -5.978652)
		(stroke
			(width 0.06985)
			(type default)
		)
		(layer "B.Cu")
	)
	(gr_line
		(start 55.999888 -3.114548)
		(end 55.999888 -5.699506)
		(stroke
			(width 0.06985)
			(type default)
		)
		(layer "B.Cu")
	)
	(gr_line
		(start 56.217312 -21.988526)
		(end 56.217312 -22.07133)
		(stroke
			(width 0.06985)
			(type default)
		)
		(layer "B.Cu")
	)
	(gr_line
		(start 56.421782 -22.2758)
		(end 56.878982 -22.2758)
		(stroke
			(width 0.06985)
			(type default)
		)
		(layer "B.Cu")
	)
	(gr_line
		(start 56.76773 -5.978652)
		(end 56.999886 -5.746496)
		(stroke
			(width 0.06985)
			(type default)
		)
		(layer "B.Cu")
	)
	(gr_line
		(start 56.878982 -22.2758)
		(end 57.107582 -22.0472)
		(stroke
			(width 0.06985)
			(type default)
		)
		(layer "B.Cu")
	)
	(gr_line
		(start 56.999378 -21.149564)
		(end 56.999632 -21.149564)
		(stroke
			(width 0.06985)
			(type default)
		)
		(layer "B.Cu")
	)
	(gr_line
		(start 56.999378 -21.149564)
		(end 57.107582 -21.257768)
		(stroke
			(width 0.06985)
			(type default)
		)
		(layer "B.Cu")
	)
	(gr_line
		(start 56.999886 -3.990848)
		(end 56.999886 -5.746496)
		(stroke
			(width 0.06985)
			(type default)
		)
		(layer "B.Cu")
	)
	(gr_line
		(start 57.107582 -21.257768)
		(end 57.107582 -22.0472)
		(stroke
			(width 0.06985)
			(type default)
		)
		(layer "B.Cu")
	)
	(gr_line
		(start 59.99988 -5.747258)
		(end 60.255404 -6.002782)
		(stroke
			(width 0.06985)
			(type default)
		)
		(layer "B.Cu")
	)
	(gr_line
		(start 59.99988 -3.114548)
		(end 59.99988 -5.747258)
		(stroke
			(width 0.06985)
			(type default)
		)
		(layer "B.Cu")
	)
	(gr_line
		(start 60.000642 -23.149814)
		(end 60.178442 -22.972014)
		(stroke
			(width 0.06985)
			(type default)
		)
		(layer "B.Cu")
	)
	(gr_line
		(start 60.178442 -22.34184)
		(end 60.178442 -22.972014)
		(stroke
			(width 0.06985)
			(type default)
		)
		(layer "B.Cu")
	)
	(gr_line
		(start 60.178442 -22.1996)
		(end 60.178442 -22.3393)
		(stroke
			(width 0.06985)
			(type default)
		)
		(layer "B.Cu")
	)
	(gr_line
		(start 60.460382 -21.9964)
		(end 60.521342 -21.9964)
		(stroke
			(width 0.06985)
			(type default)
		)
		(layer "B.Cu")
	)
	(gr_line
		(start 60.523882 -21.9964)
		(end 60.788042 -21.9964)
		(stroke
			(width 0.06985)
			(type default)
		)
		(layer "B.Cu")
	)
	(gr_line
		(start 60.7441 -6.002782)
		(end 60.999878 -5.747004)
		(stroke
			(width 0.06985)
			(type default)
		)
		(layer "B.Cu")
	)
	(gr_line
		(start 60.788042 -21.9964)
		(end 60.990988 -21.793454)
		(stroke
			(width 0.06985)
			(type default)
		)
		(layer "B.Cu")
	)
	(gr_line
		(start 60.990988 -21.149564)
		(end 60.990988 -21.793454)
		(stroke
			(width 0.06985)
			(type default)
		)
		(layer "B.Cu")
	)
	(gr_line
		(start 60.990988 -21.149564)
		(end 61.000132 -21.149564)
		(stroke
			(width 0.06985)
			(type default)
		)
		(layer "B.Cu")
	)
	(gr_line
		(start 60.999878 -3.114548)
		(end 60.999878 -5.747004)
		(stroke
			(width 0.06985)
			(type default)
		)
		(layer "B.Cu")
	)
	(gr_line
		(start 63.990728 -23.149814)
		(end 63.999872 -23.149814)
		(stroke
			(width 0.06985)
			(type default)
		)
		(layer "B.Cu")
	)
	(gr_line
		(start 63.990728 -23.149814)
		(end 64.177672 -22.96287)
		(stroke
			(width 0.06985)
			(type default)
		)
		(layer "B.Cu")
	)
	(gr_line
		(start 63.999872 -5.747258)
		(end 64.255396 -6.002782)
		(stroke
			(width 0.06985)
			(type default)
		)
		(layer "B.Cu")
	)
	(gr_line
		(start 63.999872 -3.114548)
		(end 63.999872 -5.747258)
		(stroke
			(width 0.06985)
			(type default)
		)
		(layer "B.Cu")
	)
	(gr_line
		(start 64.177672 -22.34184)
		(end 64.177672 -22.96287)
		(stroke
			(width 0.06985)
			(type default)
		)
		(layer "B.Cu")
	)
	(gr_line
		(start 64.177672 -22.1996)
		(end 64.177672 -22.3393)
		(stroke
			(width 0.06985)
			(type default)
		)
		(layer "B.Cu")
	)
	(gr_line
		(start 64.459612 -21.9964)
		(end 64.520572 -21.9964)
		(stroke
			(width 0.06985)
			(type default)
		)
		(layer "B.Cu")
	)
	(gr_line
		(start 64.523112 -21.9964)
		(end 64.787272 -21.9964)
		(stroke
			(width 0.06985)
			(type default)
		)
		(layer "B.Cu")
	)
	(gr_line
		(start 64.744092 -6.002782)
		(end 64.99987 -5.747004)
		(stroke
			(width 0.06985)
			(type default)
		)
		(layer "B.Cu")
	)
	(gr_line
		(start 64.787272 -21.9964)
		(end 64.990218 -21.793454)
		(stroke
			(width 0.06985)
			(type default)
		)
		(layer "B.Cu")
	)
	(gr_line
		(start 64.990218 -21.149564)
		(end 64.990218 -21.793454)
		(stroke
			(width 0.06985)
			(type default)
		)
		(layer "B.Cu")
	)
	(gr_line
		(start 64.990218 -21.149564)
		(end 65.000632 -21.149564)
		(stroke
			(width 0.06985)
			(type default)
		)
		(layer "B.Cu")
	)
	(gr_line
		(start 64.99987 -3.114548)
		(end 64.99987 -5.747004)
		(stroke
			(width 0.06985)
			(type default)
		)
		(layer "B.Cu")
	)
	(gr_line
		(start 67.989958 -23.149814)
		(end 68.000372 -23.149814)
		(stroke
			(width 0.06985)
			(type default)
		)
		(layer "B.Cu")
	)
	(gr_line
		(start 67.989958 -23.149814)
		(end 68.176902 -22.96287)
		(stroke
			(width 0.06985)
			(type default)
		)
		(layer "B.Cu")
	)
	(gr_line
		(start 67.999864 -5.747258)
		(end 68.255388 -6.002782)
		(stroke
			(width 0.06985)
			(type default)
		)
		(layer "B.Cu")
	)
	(gr_line
		(start 67.999864 -3.114548)
		(end 67.999864 -5.747258)
		(stroke
			(width 0.06985)
			(type default)
		)
		(layer "B.Cu")
	)
	(gr_line
		(start 68.176902 -22.34184)
		(end 68.176902 -22.96287)
		(stroke
			(width 0.06985)
			(type default)
		)
		(layer "B.Cu")
	)
	(gr_line
		(start 68.176902 -22.1996)
		(end 68.176902 -22.3393)
		(stroke
			(width 0.06985)
			(type default)
		)
		(layer "B.Cu")
	)
	(gr_line
		(start 68.458842 -21.9964)
		(end 68.519802 -21.9964)
		(stroke
			(width 0.06985)
			(type default)
		)
		(layer "B.Cu")
	)
	(gr_line
		(start 68.522342 -21.9964)
		(end 68.786502 -21.9964)
		(stroke
			(width 0.06985)
			(type default)
		)
		(layer "B.Cu")
	)
	(gr_line
		(start 68.744084 -6.002782)
		(end 68.999862 -5.747004)
		(stroke
			(width 0.06985)
			(type default)
		)
		(layer "B.Cu")
	)
	(gr_line
		(start 68.786502 -21.9964)
		(end 68.989448 -21.793454)
		(stroke
			(width 0.06985)
			(type default)
		)
		(layer "B.Cu")
	)
	(gr_line
		(start 68.989448 -21.149564)
		(end 68.989448 -21.793454)
		(stroke
			(width 0.06985)
			(type default)
		)
		(layer "B.Cu")
	)
	(gr_line
		(start 68.989448 -21.149564)
		(end 68.999862 -21.149564)
		(stroke
			(width 0.06985)
			(type default)
		)
		(layer "B.Cu")
	)
	(gr_line
		(start 68.999862 -3.114548)
		(end 68.999862 -5.747004)
		(stroke
			(width 0.06985)
			(type default)
		)
		(layer "B.Cu")
	)
	(gr_line
		(start 71.999602 -23.14956)
		(end 71.999602 -23.149814)
		(stroke
			(width 0.06985)
			(type default)
		)
		(layer "B.Cu")
	)
	(gr_line
		(start 71.999602 -23.14956)
		(end 72.144382 -23.00478)
		(stroke
			(width 0.06985)
			(type default)
		)
		(layer "B.Cu")
	)
	(gr_line
		(start 71.999856 -5.747004)
		(end 72.255634 -6.002782)
		(stroke
			(width 0.06985)
			(type default)
		)
		(layer "B.Cu")
	)
	(gr_line
		(start 71.999856 -3.114548)
		(end 71.999856 -5.747004)
		(stroke
			(width 0.06985)
			(type default)
		)
		(layer "B.Cu")
	)
	(gr_line
		(start 72.144382 -22.34184)
		(end 72.144382 -23.00478)
		(stroke
			(width 0.06985)
			(type default)
		)
		(layer "B.Cu")
	)
	(gr_line
		(start 72.144382 -22.1996)
		(end 72.144382 -22.3393)
		(stroke
			(width 0.06985)
			(type default)
		)
		(layer "B.Cu")
	)
	(gr_line
		(start 72.426322 -21.9964)
		(end 72.487282 -21.9964)
		(stroke
			(width 0.06985)
			(type default)
		)
		(layer "B.Cu")
	)
	(gr_line
		(start 72.489822 -21.9964)
		(end 72.703182 -21.9964)
		(stroke
			(width 0.06985)
			(type default)
		)
		(layer "B.Cu")
	)
	(gr_line
		(start 72.703182 -21.9964)
		(end 73.000108 -21.699474)
		(stroke
			(width 0.06985)
			(type default)
		)
		(layer "B.Cu")
	)
	(gr_line
		(start 72.74433 -6.002782)
		(end 72.999854 -5.747258)
		(stroke
			(width 0.06985)
			(type default)
		)
		(layer "B.Cu")
	)
	(gr_line
		(start 72.999854 -3.114548)
		(end 72.999854 -5.747258)
		(stroke
			(width 0.06985)
			(type default)
		)
		(layer "B.Cu")
	)
	(gr_line
		(start 73.000108 -21.149564)
		(end 73.000108 -21.699474)
		(stroke
			(width 0.06985)
			(type default)
		)
		(layer "B.Cu")
	)
	(gr_line
		(start 73.000108 -21.149564)
		(end 73.000362 -21.149564)
		(stroke
			(width 0.06985)
			(type default)
		)
		(layer "B.Cu")
	)
	(gr_line
		(start 80.000094 -5.747258)
		(end 80.255618 -6.002782)
		(stroke
			(width 0.06985)
			(type default)
		)
		(layer "B.Cu")
	)
	(gr_line
		(start 80.000094 -3.114548)
		(end 80.000094 -5.747258)
		(stroke
			(width 0.06985)
			(type default)
		)
		(layer "B.Cu")
	)
	(gr_line
		(start 80.000602 -23.14956)
		(end 80.000602 -23.149814)
		(stroke
			(width 0.06985)
			(type default)
		)
		(layer "B.Cu")
	)
	(gr_line
		(start 80.000602 -23.14956)
		(end 80.282542 -22.86762)
		(stroke
			(width 0.06985)
			(type default)
		)
		(layer "B.Cu")
	)
	(gr_line
		(start 80.106012 -22.05863)
		(end 80.282542 -22.23516)
		(stroke
			(width 0.06985)
			(type default)
		)
		(layer "B.Cu")
	)
	(gr_line
		(start 80.282542 -22.408134)
		(end 80.282542 -22.86762)
		(stroke
			(width 0.06985)
			(type default)
		)
		(layer "B.Cu")
	)
	(gr_line
		(start 80.282542 -22.23516)
		(end 80.282542 -22.405594)
		(stroke
			(width 0.06985)
			(type default)
		)
		(layer "B.Cu")
	)
	(gr_line
		(start 80.589882 -22.0599)
		(end 80.592676 -22.062694)
		(stroke
			(width 0.06985)
			(type default)
		)
		(layer "B.Cu")
	)
	(gr_line
		(start 80.589882 -22.05736)
		(end 80.589882 -22.0599)
		(stroke
			(width 0.06985)
			(type default)
		)
		(layer "B.Cu")
	)
	(gr_line
		(start 80.592676 -22.062694)
		(end 80.625442 -22.062694)
		(stroke
			(width 0.06985)
			(type default)
		)
		(layer "B.Cu")
	)
	(gr_line
		(start 80.627982 -22.062694)
		(end 80.790288 -22.062694)
		(stroke
			(width 0.06985)
			(type default)
		)
		(layer "B.Cu")
	)
	(gr_line
		(start 80.744314 -6.002782)
		(end 81.000092 -5.747004)
		(stroke
			(width 0.06985)
			(type default)
		)
		(layer "B.Cu")
	)
	(gr_line
		(start 80.790288 -22.062694)
		(end 80.999838 -21.853144)
		(stroke
			(width 0.06985)
			(type default)
		)
		(layer "B.Cu")
	)
	(gr_line
		(start 80.999838 -21.149564)
		(end 80.999838 -21.853144)
		(stroke
			(width 0.06985)
			(type default)
		)
		(layer "B.Cu")
	)
	(gr_line
		(start 80.999838 -21.149564)
		(end 81.000092 -21.149564)
		(stroke
			(width 0.06985)
			(type default)
		)
		(layer "B.Cu")
	)
	(gr_line
		(start 81.000092 -3.114548)
		(end 81.000092 -5.747004)
		(stroke
			(width 0.06985)
			(type default)
		)
		(layer "B.Cu")
	)
	(gr_arc
		(start 0 -26.100024)
		(mid 0.292893 -26.807129)
		(end 0.999998 -27.100022)
		(stroke
			(width 1.524)
			(type default)
		)
		(layer "In1.Cu")
	)
	(gr_line
		(start 0 -9.59993)
		(end 0 -26.100024)
		(stroke
			(width 1.524)
			(type default)
		)
		(layer "In1.Cu")
	)
	(gr_line
		(start 0.999998 -27.100022)
		(end 36.500054 -27.100022)
		(stroke
			(width 1.524)
			(type default)
		)
		(layer "In1.Cu")
	)
	(gr_arc
		(start 0.999998 -8.599932)
		(mid 0.292893 -8.892825)
		(end 0 -9.59993)
		(stroke
			(width 1.524)
			(type default)
		)
		(layer "In1.Cu")
	)
	(gr_line
		(start 4.350004 -8.599932)
		(end 0.999998 -8.599932)
		(stroke
			(width 1.524)
			(type default)
		)
		(layer "In1.Cu")
	)
	(gr_arc
		(start 4.350004 -8.599932)
		(mid 5.057108 -8.307038)
		(end 5.350002 -7.599934)
		(stroke
			(width 1.524)
			(type default)
		)
		(layer "In1.Cu")
	)
	(gr_line
		(start 5.350002 -7.599934)
		(end 8.999982 -11.249914)
		(stroke
			(width 0.381)
			(type default)
		)
		(layer "In1.Cu")
	)
	(gr_line
		(start 5.350002 -0.500126)
		(end 5.350002 -7.599934)
		(stroke
			(width 1.524)
			(type default)
		)
		(layer "In1.Cu")
	)
	(gr_line
		(start 5.849874 0)
		(end 5.350002 -0.500126)
		(stroke
			(width 1.524)
			(type default)
		)
		(layer "In1.Cu")
	)
	(gr_line
		(start 8.999982 -17.0942)
		(end 10.015982 -18.1102)
		(stroke
			(width 0.381)
			(type default)
		)
		(layer "In1.Cu")
	)
	(gr_line
		(start 8.999982 -11.249914)
		(end 8.999982 -17.0942)
		(stroke
			(width 0.381)
			(type default)
		)
		(layer "In1.Cu")
	)
	(gr_line
		(start 10.015982 -19.2532)
		(end 10.473182 -19.7104)
		(stroke
			(width 0.381)
			(type default)
		)
		(layer "In1.Cu")
	)
	(gr_line
		(start 10.015982 -18.1102)
		(end 10.015982 -19.2532)
		(stroke
			(width 0.381)
			(type default)
		)
		(layer "In1.Cu")
	)
	(gr_line
		(start 10.473182 -19.7104)
		(end 79.385922 -19.7104)
		(stroke
			(width 0.381)
			(type default)
		)
		(layer "In1.Cu")
	)
	(gr_arc
		(start 36.500054 -27.100022)
		(mid 37.207159 -26.807129)
		(end 37.500052 -26.100024)
		(stroke
			(width 1.524)
			(type default)
		)
		(layer "In1.Cu")
	)
	(gr_arc
		(start 38.50005 -25.100026)
		(mid 37.792985 -25.392938)
		(end 37.500052 -26.100024)
		(stroke
			(width 1.524)
			(type default)
		)
		(layer "In1.Cu")
	)
	(gr_line
		(start 38.50005 -25.100026)
		(end 56.500014 -25.100026)
		(stroke
			(width 1.524)
			(type default)
		)
		(layer "In1.Cu")
	)
	(gr_arc
		(start 57.500012 -26.100024)
		(mid 57.207129 -25.392898)
		(end 56.500014 -25.100026)
		(stroke
			(width 1.524)
			(type default)
		)
		(layer "In1.Cu")
	)
	(gr_arc
		(start 57.500012 -26.100024)
		(mid 57.792905 -26.807129)
		(end 58.50001 -27.100022)
		(stroke
			(width 1.524)
			(type default)
		)
		(layer "In1.Cu")
	)
	(gr_line
		(start 58.50001 -27.100022)
		(end 94.000066 -27.100022)
		(stroke
			(width 1.524)
			(type default)
		)
		(layer "In1.Cu")
	)
	(gr_arc
		(start 64.749934 -14.100048)
		(mid 65.042827 -14.807153)
		(end 65.749932 -15.100046)
		(stroke
			(width 0.508)
			(type default)
		)
		(layer "In1.Cu")
	)
	(gr_line
		(start 64.749934 -11.100054)
		(end 64.749934 -14.100048)
		(stroke
			(width 0.508)
			(type default)
		)
		(layer "In1.Cu")
	)
	(gr_line
		(start 65.749932 -15.100046)
		(end 68.749926 -15.100046)
		(stroke
			(width 0.508)
			(type default)
		)
		(layer "In1.Cu")
	)
	(gr_arc
		(start 65.749932 -10.100056)
		(mid 65.042827 -10.392949)
		(end 64.749934 -11.100054)
		(stroke
			(width 0.508)
			(type default)
		)
		(layer "In1.Cu")
	)
	(gr_arc
		(start 68.749926 -15.100046)
		(mid 69.457031 -14.807153)
		(end 69.749924 -14.100048)
		(stroke
			(width 0.508)
			(type default)
		)
		(layer "In1.Cu")
	)
	(gr_line
		(start 68.749926 -10.100056)
		(end 65.749932 -10.100056)
		(stroke
			(width 0.508)
			(type default)
		)
		(layer "In1.Cu")
	)
	(gr_line
		(start 69.749924 -14.100048)
		(end 69.749924 -11.100054)
		(stroke
			(width 0.508)
			(type default)
		)
		(layer "In1.Cu")
	)
	(gr_arc
		(start 69.749924 -11.100054)
		(mid 69.457031 -10.392949)
		(end 68.749926 -10.100056)
		(stroke
			(width 0.508)
			(type default)
		)
		(layer "In1.Cu")
	)
	(gr_arc
		(start 71.34987 -14.100048)
		(mid 71.642763 -14.807153)
		(end 72.349868 -15.100046)
		(stroke
			(width 0.508)
			(type default)
		)
		(layer "In1.Cu")
	)
	(gr_line
		(start 71.34987 -11.100054)
		(end 71.34987 -14.100048)
		(stroke
			(width 0.508)
			(type default)
		)
		(layer "In1.Cu")
	)
	(gr_line
		(start 72.349868 -15.100046)
		(end 75.349862 -15.100046)
		(stroke
			(width 0.508)
			(type default)
		)
		(layer "In1.Cu")
	)
	(gr_arc
		(start 72.349868 -10.100056)
		(mid 71.642763 -10.392949)
		(end 71.34987 -11.100054)
		(stroke
			(width 0.508)
			(type default)
		)
		(layer "In1.Cu")
	)
	(gr_arc
		(start 75.349862 -15.100046)
		(mid 76.056967 -14.807153)
		(end 76.34986 -14.100048)
		(stroke
			(width 0.508)
			(type default)
		)
		(layer "In1.Cu")
	)
	(gr_line
		(start 75.349862 -10.100056)
		(end 72.349868 -10.100056)
		(stroke
			(width 0.508)
			(type default)
		)
		(layer "In1.Cu")
	)
	(gr_line
		(start 76.049886 0)
		(end 5.849874 0)
		(stroke
			(width 11.176)
			(type default)
		)
		(layer "In1.Cu")
	)
	(gr_line
		(start 76.34986 -14.100048)
		(end 76.34986 -11.100054)
		(stroke
			(width 0.508)
			(type default)
		)
		(layer "In1.Cu")
	)
	(gr_arc
		(start 76.34986 -11.100054)
		(mid 76.056967 -10.392949)
		(end 75.349862 -10.100056)
		(stroke
			(width 0.508)
			(type default)
		)
		(layer "In1.Cu")
	)
	(gr_line
		(start 76.550012 -7.450074)
		(end 76.550012 -0.500126)
		(stroke
			(width 1.524)
			(type default)
		)
		(layer "In1.Cu")
	)
	(gr_arc
		(start 76.550012 -7.450074)
		(mid 77.499972 -8.400034)
		(end 78.449932 -7.450074)
		(stroke
			(width 1.524)
			(type default)
		)
		(layer "In1.Cu")
	)
	(gr_line
		(start 76.550012 -0.500126)
		(end 76.049886 0)
		(stroke
			(width 1.524)
			(type default)
		)
		(layer "In1.Cu")
	)
	(gr_arc
		(start 77.95006 -14.100048)
		(mid 78.242953 -14.807153)
		(end 78.950058 -15.100046)
		(stroke
			(width 0.508)
			(type default)
		)
		(layer "In1.Cu")
	)
	(gr_line
		(start 77.95006 -11.100054)
		(end 77.95006 -14.100048)
		(stroke
			(width 0.508)
			(type default)
		)
		(layer "In1.Cu")
	)
	(gr_line
		(start 78.449932 -9.899904)
		(end 78.650084 -10.100056)
		(stroke
			(width 0.381)
			(type default)
		)
		(layer "In1.Cu")
	)
	(gr_line
		(start 78.449932 -7.450074)
		(end 78.449932 -9.899904)
		(stroke
			(width 0.381)
			(type default)
		)
		(layer "In1.Cu")
	)
	(gr_line
		(start 78.449932 -0.500126)
		(end 78.449932 -7.450074)
		(stroke
			(width 1.524)
			(type default)
		)
		(layer "In1.Cu")
	)
	(gr_line
		(start 78.650084 -10.100056)
		(end 78.950058 -10.100056)
		(stroke
			(width 0.381)
			(type default)
		)
		(layer "In1.Cu")
	)
	(gr_line
		(start 78.950058 -17.118076)
		(end 78.950058 -15.40002)
		(stroke
			(width 0.381)
			(type default)
		)
		(layer "In1.Cu")
	)
	(gr_line
		(start 78.950058 -15.100046)
		(end 81.950052 -15.100046)
		(stroke
			(width 0.508)
			(type default)
		)
		(layer "In1.Cu")
	)
	(gr_arc
		(start 78.950058 -10.100056)
		(mid 78.242953 -10.392949)
		(end 77.95006 -11.100054)
		(stroke
			(width 0.508)
			(type default)
		)
		(layer "In1.Cu")
	)
	(gr_line
		(start 78.950058 0)
		(end 78.449932 -0.500126)
		(stroke
			(width 1.524)
			(type default)
		)
		(layer "In1.Cu")
	)
	(gr_line
		(start 79.385922 -19.7104)
		(end 79.942182 -19.15414)
		(stroke
			(width 0.381)
			(type default)
		)
		(layer "In1.Cu")
	)
	(gr_line
		(start 79.942182 -19.15414)
		(end 79.942182 -18.1102)
		(stroke
			(width 0.381)
			(type default)
		)
		(layer "In1.Cu")
	)
	(gr_line
		(start 79.942182 -18.1102)
		(end 78.950058 -17.118076)
		(stroke
			(width 0.381)
			(type default)
		)
		(layer "In1.Cu")
	)
	(gr_arc
		(start 81.950052 -15.100046)
		(mid 82.657157 -14.807153)
		(end 82.95005 -14.100048)
		(stroke
			(width 0.508)
			(type default)
		)
		(layer "In1.Cu")
	)
	(gr_line
		(start 81.950052 -10.100056)
		(end 78.950058 -10.100056)
		(stroke
			(width 0.508)
			(type default)
		)
		(layer "In1.Cu")
	)
	(gr_line
		(start 82.95005 -14.100048)
		(end 82.95005 -11.100054)
		(stroke
			(width 0.508)
			(type default)
		)
		(layer "In1.Cu")
	)
	(gr_arc
		(start 82.95005 -11.100054)
		(mid 82.657157 -10.392949)
		(end 81.950052 -10.100056)
		(stroke
			(width 0.508)
			(type default)
		)
		(layer "In1.Cu")
	)
	(gr_line
		(start 89.149936 0)
		(end 78.950058 0)
		(stroke
			(width 11.176)
			(type default)
		)
		(layer "In1.Cu")
	)
	(gr_line
		(start 89.650062 -15.225014)
		(end 89.650062 -0.500126)
		(stroke
			(width 1.524)
			(type default)
		)
		(layer "In1.Cu")
	)
	(gr_arc
		(start 89.650062 -15.225014)
		(mid 89.942957 -15.932124)
		(end 90.65006 -16.225012)
		(stroke
			(width 1.524)
			(type default)
		)
		(layer "In1.Cu")
	)
	(gr_line
		(start 89.650062 -0.500126)
		(end 89.149936 0)
		(stroke
			(width 1.524)
			(type default)
		)
		(layer "In1.Cu")
	)
	(gr_arc
		(start 94.000066 -27.100022)
		(mid 94.707171 -26.807129)
		(end 95.000064 -26.100024)
		(stroke
			(width 1.524)
			(type default)
		)
		(layer "In1.Cu")
	)
	(gr_line
		(start 94.000066 -16.225012)
		(end 90.65006 -16.225012)
		(stroke
			(width 1.524)
			(type default)
		)
		(layer "In1.Cu")
	)
	(gr_line
		(start 95.000064 -26.100024)
		(end 95.000064 -17.22501)
		(stroke
			(width 1.524)
			(type default)
		)
		(layer "In1.Cu")
	)
	(gr_arc
		(start 95.000064 -17.22501)
		(mid 94.707171 -16.517905)
		(end 94.000066 -16.225012)
		(stroke
			(width 1.524)
			(type default)
		)
		(layer "In1.Cu")
	)
	(gr_arc
		(start 0 -26.100024)
		(mid 0.292893 -26.807129)
		(end 0.999998 -27.100022)
		(stroke
			(width 1.524)
			(type default)
		)
		(layer "In2.Cu")
	)
	(gr_line
		(start 0 -9.59993)
		(end 0 -26.100024)
		(stroke
			(width 1.524)
			(type default)
		)
		(layer "In2.Cu")
	)
	(gr_line
		(start 0.999998 -27.100022)
		(end 36.500054 -27.100022)
		(stroke
			(width 1.524)
			(type default)
		)
		(layer "In2.Cu")
	)
	(gr_arc
		(start 0.999998 -8.599932)
		(mid 0.292893 -8.892825)
		(end 0 -9.59993)
		(stroke
			(width 1.524)
			(type default)
		)
		(layer "In2.Cu")
	)
	(gr_line
		(start 4.350004 -8.599932)
		(end 0.999998 -8.599932)
		(stroke
			(width 1.524)
			(type default)
		)
		(layer "In2.Cu")
	)
	(gr_arc
		(start 4.350004 -8.599932)
		(mid 5.057108 -8.307038)
		(end 5.350002 -7.599934)
		(stroke
			(width 1.524)
			(type default)
		)
		(layer "In2.Cu")
	)
	(gr_line
		(start 5.350002 -0.500126)
		(end 5.350002 -7.599934)
		(stroke
			(width 1.524)
			(type default)
		)
		(layer "In2.Cu")
	)
	(gr_line
		(start 5.849874 0)
		(end 5.350002 -0.500126)
		(stroke
			(width 1.524)
			(type default)
		)
		(layer "In2.Cu")
	)
	(gr_arc
		(start 36.500054 -27.100022)
		(mid 37.207159 -26.807129)
		(end 37.500052 -26.100024)
		(stroke
			(width 1.524)
			(type default)
		)
		(layer "In2.Cu")
	)
	(gr_arc
		(start 38.50005 -25.100026)
		(mid 37.792985 -25.392938)
		(end 37.500052 -26.100024)
		(stroke
			(width 1.524)
			(type default)
		)
		(layer "In2.Cu")
	)
	(gr_line
		(start 38.50005 -25.100026)
		(end 56.500014 -25.100026)
		(stroke
			(width 1.524)
			(type default)
		)
		(layer "In2.Cu")
	)
	(gr_arc
		(start 57.500012 -26.100024)
		(mid 57.207129 -25.392898)
		(end 56.500014 -25.100026)
		(stroke
			(width 1.524)
			(type default)
		)
		(layer "In2.Cu")
	)
	(gr_arc
		(start 57.500012 -26.100024)
		(mid 57.792905 -26.807129)
		(end 58.50001 -27.100022)
		(stroke
			(width 1.524)
			(type default)
		)
		(layer "In2.Cu")
	)
	(gr_line
		(start 58.50001 -27.100022)
		(end 94.000066 -27.100022)
		(stroke
			(width 1.524)
			(type default)
		)
		(layer "In2.Cu")
	)
	(gr_arc
		(start 64.749934 -14.100048)
		(mid 65.042827 -14.807153)
		(end 65.749932 -15.100046)
		(stroke
			(width 0.508)
			(type default)
		)
		(layer "In2.Cu")
	)
	(gr_line
		(start 64.749934 -11.100054)
		(end 64.749934 -14.100048)
		(stroke
			(width 0.508)
			(type default)
		)
		(layer "In2.Cu")
	)
	(gr_line
		(start 65.749932 -15.100046)
		(end 68.749926 -15.100046)
		(stroke
			(width 0.508)
			(type default)
		)
		(layer "In2.Cu")
	)
	(gr_arc
		(start 65.749932 -10.100056)
		(mid 65.042827 -10.392949)
		(end 64.749934 -11.100054)
		(stroke
			(width 0.508)
			(type default)
		)
		(layer "In2.Cu")
	)
	(gr_arc
		(start 68.749926 -15.100046)
		(mid 69.457031 -14.807153)
		(end 69.749924 -14.100048)
		(stroke
			(width 0.508)
			(type default)
		)
		(layer "In2.Cu")
	)
	(gr_line
		(start 68.749926 -10.100056)
		(end 65.749932 -10.100056)
		(stroke
			(width 0.508)
			(type default)
		)
		(layer "In2.Cu")
	)
	(gr_line
		(start 69.749924 -14.100048)
		(end 69.749924 -11.100054)
		(stroke
			(width 0.508)
			(type default)
		)
		(layer "In2.Cu")
	)
	(gr_arc
		(start 69.749924 -11.100054)
		(mid 69.457031 -10.392949)
		(end 68.749926 -10.100056)
		(stroke
			(width 0.508)
			(type default)
		)
		(layer "In2.Cu")
	)
	(gr_arc
		(start 71.34987 -14.100048)
		(mid 71.642763 -14.807153)
		(end 72.349868 -15.100046)
		(stroke
			(width 0.508)
			(type default)
		)
		(layer "In2.Cu")
	)
	(gr_line
		(start 71.34987 -11.100054)
		(end 71.34987 -14.100048)
		(stroke
			(width 0.508)
			(type default)
		)
		(layer "In2.Cu")
	)
	(gr_line
		(start 72.349868 -15.100046)
		(end 75.349862 -15.100046)
		(stroke
			(width 0.508)
			(type default)
		)
		(layer "In2.Cu")
	)
	(gr_arc
		(start 72.349868 -10.100056)
		(mid 71.642763 -10.392949)
		(end 71.34987 -11.100054)
		(stroke
			(width 0.508)
			(type default)
		)
		(layer "In2.Cu")
	)
	(gr_arc
		(start 75.349862 -15.100046)
		(mid 76.056967 -14.807153)
		(end 76.34986 -14.100048)
		(stroke
			(width 0.508)
			(type default)
		)
		(layer "In2.Cu")
	)
	(gr_line
		(start 75.349862 -10.100056)
		(end 72.349868 -10.100056)
		(stroke
			(width 0.508)
			(type default)
		)
		(layer "In2.Cu")
	)
	(gr_line
		(start 76.049886 0)
		(end 5.849874 0)
		(stroke
			(width 11.176)
			(type default)
		)
		(layer "In2.Cu")
	)
	(gr_line
		(start 76.34986 -14.100048)
		(end 76.34986 -11.100054)
		(stroke
			(width 0.508)
			(type default)
		)
		(layer "In2.Cu")
	)
	(gr_arc
		(start 76.34986 -11.100054)
		(mid 76.056967 -10.392949)
		(end 75.349862 -10.100056)
		(stroke
			(width 0.508)
			(type default)
		)
		(layer "In2.Cu")
	)
	(gr_line
		(start 76.550012 -7.450074)
		(end 76.550012 -0.500126)
		(stroke
			(width 1.524)
			(type default)
		)
		(layer "In2.Cu")
	)
	(gr_arc
		(start 76.550012 -7.450074)
		(mid 77.499972 -8.400034)
		(end 78.449932 -7.450074)
		(stroke
			(width 1.524)
			(type default)
		)
		(layer "In2.Cu")
	)
	(gr_line
		(start 76.550012 -0.500126)
		(end 76.049886 0)
		(stroke
			(width 1.524)
			(type default)
		)
		(layer "In2.Cu")
	)
	(gr_arc
		(start 77.95006 -14.100048)
		(mid 78.242953 -14.807153)
		(end 78.950058 -15.100046)
		(stroke
			(width 0.508)
			(type default)
		)
		(layer "In2.Cu")
	)
	(gr_line
		(start 77.95006 -11.100054)
		(end 77.95006 -14.100048)
		(stroke
			(width 0.508)
			(type default)
		)
		(layer "In2.Cu")
	)
	(gr_line
		(start 78.449932 -0.500126)
		(end 78.449932 -7.450074)
		(stroke
			(width 1.524)
			(type default)
		)
		(layer "In2.Cu")
	)
	(gr_line
		(start 78.950058 -15.100046)
		(end 81.950052 -15.100046)
		(stroke
			(width 0.508)
			(type default)
		)
		(layer "In2.Cu")
	)
	(gr_arc
		(start 78.950058 -10.100056)
		(mid 78.242953 -10.392949)
		(end 77.95006 -11.100054)
		(stroke
			(width 0.508)
			(type default)
		)
		(layer "In2.Cu")
	)
	(gr_line
		(start 78.950058 0)
		(end 78.449932 -0.500126)
		(stroke
			(width 1.524)
			(type default)
		)
		(layer "In2.Cu")
	)
	(gr_arc
		(start 81.950052 -15.100046)
		(mid 82.657157 -14.807153)
		(end 82.95005 -14.100048)
		(stroke
			(width 0.508)
			(type default)
		)
		(layer "In2.Cu")
	)
	(gr_line
		(start 81.950052 -10.100056)
		(end 78.950058 -10.100056)
		(stroke
			(width 0.508)
			(type default)
		)
		(layer "In2.Cu")
	)
	(gr_line
		(start 82.95005 -14.100048)
		(end 82.95005 -11.100054)
		(stroke
			(width 0.508)
			(type default)
		)
		(layer "In2.Cu")
	)
	(gr_arc
		(start 82.95005 -11.100054)
		(mid 82.657157 -10.392949)
		(end 81.950052 -10.100056)
		(stroke
			(width 0.508)
			(type default)
		)
		(layer "In2.Cu")
	)
	(gr_line
		(start 89.149936 0)
		(end 78.950058 0)
		(stroke
			(width 11.176)
			(type default)
		)
		(layer "In2.Cu")
	)
	(gr_line
		(start 89.650062 -15.225014)
		(end 89.650062 -0.500126)
		(stroke
			(width 1.524)
			(type default)
		)
		(layer "In2.Cu")
	)
	(gr_arc
		(start 89.650062 -15.225014)
		(mid 89.942957 -15.932124)
		(end 90.65006 -16.225012)
		(stroke
			(width 1.524)
			(type default)
		)
		(layer "In2.Cu")
	)
	(gr_line
		(start 89.650062 -0.500126)
		(end 89.149936 0)
		(stroke
			(width 1.524)
			(type default)
		)
		(layer "In2.Cu")
	)
	(gr_arc
		(start 94.000066 -27.100022)
		(mid 94.707171 -26.807129)
		(end 95.000064 -26.100024)
		(stroke
			(width 1.524)
			(type default)
		)
		(layer "In2.Cu")
	)
	(gr_line
		(start 94.000066 -16.225012)
		(end 90.65006 -16.225012)
		(stroke
			(width 1.524)
			(type default)
		)
		(layer "In2.Cu")
	)
	(gr_line
		(start 95.000064 -26.100024)
		(end 95.000064 -17.22501)
		(stroke
			(width 1.524)
			(type default)
		)
		(layer "In2.Cu")
	)
	(gr_arc
		(start 95.000064 -17.22501)
		(mid 94.707171 -16.517905)
		(end 94.000066 -16.225012)
		(stroke
			(width 1.524)
			(type default)
		)
		(layer "In2.Cu")
	)
	(gr_arc
		(start 0 -26.100024)
		(mid 0.292893 -26.807129)
		(end 0.999998 -27.100022)
		(stroke
			(width 0.05)
			(type default)
		)
		(layer "Edge.Cuts")
	)
	(gr_line
		(start 0 -9.59993)
		(end 0 -26.100024)
		(stroke
			(width 0.05)
			(type default)
		)
		(layer "Edge.Cuts")
	)
	(gr_line
		(start 0.999998 -27.100022)
		(end 36.500054 -27.100022)
		(stroke
			(width 0.05)
			(type default)
		)
		(layer "Edge.Cuts")
	)
	(gr_arc
		(start 0.999998 -8.599932)
		(mid 0.292893 -8.892825)
		(end 0 -9.59993)
		(stroke
			(width 0.05)
			(type default)
		)
		(layer "Edge.Cuts")
	)
	(gr_line
		(start 4.350004 -8.599932)
		(end 0.999998 -8.599932)
		(stroke
			(width 0.05)
			(type default)
		)
		(layer "Edge.Cuts")
	)
	(gr_arc
		(start 4.350004 -8.599932)
		(mid 5.057108 -8.307038)
		(end 5.350002 -7.599934)
		(stroke
			(width 0.05)
			(type default)
		)
		(layer "Edge.Cuts")
	)
	(gr_line
		(start 5.350002 -0.500126)
		(end 5.350002 -7.599934)
		(stroke
			(width 0.05)
			(type default)
		)
		(layer "Edge.Cuts")
	)
	(gr_line
		(start 5.849874 0)
		(end 5.350002 -0.500126)
		(stroke
			(width 0.05)
			(type default)
		)
		(layer "Edge.Cuts")
	)
	(gr_arc
		(start 36.500054 -27.100022)
		(mid 37.207159 -26.807129)
		(end 37.500052 -26.100024)
		(stroke
			(width 0.05)
			(type default)
		)
		(layer "Edge.Cuts")
	)
	(gr_arc
		(start 38.50005 -25.100026)
		(mid 37.792985 -25.392938)
		(end 37.500052 -26.100024)
		(stroke
			(width 0.05)
			(type default)
		)
		(layer "Edge.Cuts")
	)
	(gr_line
		(start 38.50005 -25.100026)
		(end 56.500014 -25.100026)
		(stroke
			(width 0.05)
			(type default)
		)
		(layer "Edge.Cuts")
	)
	(gr_arc
		(start 57.500012 -26.100024)
		(mid 57.207129 -25.392898)
		(end 56.500014 -25.100026)
		(stroke
			(width 0.05)
			(type default)
		)
		(layer "Edge.Cuts")
	)
	(gr_arc
		(start 57.500012 -26.100024)
		(mid 57.792905 -26.807129)
		(end 58.50001 -27.100022)
		(stroke
			(width 0.05)
			(type default)
		)
		(layer "Edge.Cuts")
	)
	(gr_line
		(start 58.50001 -27.100022)
		(end 94.000066 -27.100022)
		(stroke
			(width 0.05)
			(type default)
		)
		(layer "Edge.Cuts")
	)
	(gr_arc
		(start 64.749934 -14.100048)
		(mid 65.042827 -14.807153)
		(end 65.749932 -15.100046)
		(stroke
			(width 0.05)
			(type default)
		)
		(layer "Edge.Cuts")
	)
	(gr_line
		(start 64.749934 -11.100054)
		(end 64.749934 -14.100048)
		(stroke
			(width 0.05)
			(type default)
		)
		(layer "Edge.Cuts")
	)
	(gr_line
		(start 65.749932 -15.100046)
		(end 68.749926 -15.100046)
		(stroke
			(width 0.05)
			(type default)
		)
		(layer "Edge.Cuts")
	)
	(gr_arc
		(start 65.749932 -10.100056)
		(mid 65.042827 -10.392949)
		(end 64.749934 -11.100054)
		(stroke
			(width 0.05)
			(type default)
		)
		(layer "Edge.Cuts")
	)
	(gr_arc
		(start 68.749926 -15.100046)
		(mid 69.457031 -14.807153)
		(end 69.749924 -14.100048)
		(stroke
			(width 0.05)
			(type default)
		)
		(layer "Edge.Cuts")
	)
	(gr_line
		(start 68.749926 -10.100056)
		(end 65.749932 -10.100056)
		(stroke
			(width 0.05)
			(type default)
		)
		(layer "Edge.Cuts")
	)
	(gr_line
		(start 69.749924 -14.100048)
		(end 69.749924 -11.100054)
		(stroke
			(width 0.05)
			(type default)
		)
		(layer "Edge.Cuts")
	)
	(gr_arc
		(start 69.749924 -11.100054)
		(mid 69.457031 -10.392949)
		(end 68.749926 -10.100056)
		(stroke
			(width 0.05)
			(type default)
		)
		(layer "Edge.Cuts")
	)
	(gr_arc
		(start 71.350124 -14.100048)
		(mid 71.643017 -14.807153)
		(end 72.350122 -15.100046)
		(stroke
			(width 0.05)
			(type default)
		)
		(layer "Edge.Cuts")
	)
	(gr_line
		(start 71.350124 -11.100054)
		(end 71.350124 -14.100048)
		(stroke
			(width 0.05)
			(type default)
		)
		(layer "Edge.Cuts")
	)
	(gr_line
		(start 72.350122 -15.100046)
		(end 75.350116 -15.100046)
		(stroke
			(width 0.05)
			(type default)
		)
		(layer "Edge.Cuts")
	)
	(gr_arc
		(start 72.350122 -10.100056)
		(mid 71.643017 -10.392949)
		(end 71.350124 -11.100054)
		(stroke
			(width 0.05)
			(type default)
		)
		(layer "Edge.Cuts")
	)
	(gr_arc
		(start 75.350116 -15.100046)
		(mid 76.057221 -14.807153)
		(end 76.350114 -14.100048)
		(stroke
			(width 0.05)
			(type default)
		)
		(layer "Edge.Cuts")
	)
	(gr_line
		(start 75.350116 -10.100056)
		(end 72.350122 -10.100056)
		(stroke
			(width 0.05)
			(type default)
		)
		(layer "Edge.Cuts")
	)
	(gr_line
		(start 76.049886 0)
		(end 5.849874 0)
		(stroke
			(width 0.05)
			(type default)
		)
		(layer "Edge.Cuts")
	)
	(gr_line
		(start 76.350114 -14.100048)
		(end 76.350114 -11.100054)
		(stroke
			(width 0.05)
			(type default)
		)
		(layer "Edge.Cuts")
	)
	(gr_arc
		(start 76.350114 -11.100054)
		(mid 76.057221 -10.392949)
		(end 75.350116 -10.100056)
		(stroke
			(width 0.05)
			(type default)
		)
		(layer "Edge.Cuts")
	)
	(gr_line
		(start 76.550012 -7.450074)
		(end 76.550012 -0.500126)
		(stroke
			(width 0.05)
			(type default)
		)
		(layer "Edge.Cuts")
	)
	(gr_arc
		(start 76.550012 -7.450074)
		(mid 77.499972 -8.400034)
		(end 78.449932 -7.450074)
		(stroke
			(width 0.05)
			(type default)
		)
		(layer "Edge.Cuts")
	)
	(gr_line
		(start 76.550012 -0.500126)
		(end 76.049886 0)
		(stroke
			(width 0.05)
			(type default)
		)
		(layer "Edge.Cuts")
	)
	(gr_arc
		(start 77.95006 -14.100048)
		(mid 78.242953 -14.807153)
		(end 78.950058 -15.100046)
		(stroke
			(width 0.05)
			(type default)
		)
		(layer "Edge.Cuts")
	)
	(gr_line
		(start 77.95006 -11.100054)
		(end 77.95006 -14.100048)
		(stroke
			(width 0.05)
			(type default)
		)
		(layer "Edge.Cuts")
	)
	(gr_line
		(start 78.449932 -0.500126)
		(end 78.449932 -7.450074)
		(stroke
			(width 0.05)
			(type default)
		)
		(layer "Edge.Cuts")
	)
	(gr_line
		(start 78.950058 -15.100046)
		(end 81.950052 -15.100046)
		(stroke
			(width 0.05)
			(type default)
		)
		(layer "Edge.Cuts")
	)
	(gr_arc
		(start 78.950058 -10.100056)
		(mid 78.242953 -10.392949)
		(end 77.95006 -11.100054)
		(stroke
			(width 0.05)
			(type default)
		)
		(layer "Edge.Cuts")
	)
	(gr_line
		(start 78.950058 0)
		(end 78.449932 -0.500126)
		(stroke
			(width 0.05)
			(type default)
		)
		(layer "Edge.Cuts")
	)
	(gr_arc
		(start 81.950052 -15.100046)
		(mid 82.657157 -14.807153)
		(end 82.95005 -14.100048)
		(stroke
			(width 0.05)
			(type default)
		)
		(layer "Edge.Cuts")
	)
	(gr_line
		(start 81.950052 -10.100056)
		(end 78.950058 -10.100056)
		(stroke
			(width 0.05)
			(type default)
		)
		(layer "Edge.Cuts")
	)
	(gr_line
		(start 82.95005 -14.100048)
		(end 82.95005 -11.100054)
		(stroke
			(width 0.05)
			(type default)
		)
		(layer "Edge.Cuts")
	)
	(gr_arc
		(start 82.95005 -11.100054)
		(mid 82.657157 -10.392949)
		(end 81.950052 -10.100056)
		(stroke
			(width 0.05)
			(type default)
		)
		(layer "Edge.Cuts")
	)
	(gr_line
		(start 89.149936 0)
		(end 78.950058 0)
		(stroke
			(width 0.05)
			(type default)
		)
		(layer "Edge.Cuts")
	)
	(gr_line
		(start 89.650062 -15.225014)
		(end 89.650062 -0.500126)
		(stroke
			(width 0.05)
			(type default)
		)
		(layer "Edge.Cuts")
	)
	(gr_arc
		(start 89.650062 -15.225014)
		(mid 89.942957 -15.932124)
		(end 90.65006 -16.225012)
		(stroke
			(width 0.05)
			(type default)
		)
		(layer "Edge.Cuts")
	)
	(gr_line
		(start 89.650062 -0.500126)
		(end 89.149936 0)
		(stroke
			(width 0.05)
			(type default)
		)
		(layer "Edge.Cuts")
	)
	(gr_arc
		(start 94.000066 -27.100022)
		(mid 94.707171 -26.807129)
		(end 95.000064 -26.100024)
		(stroke
			(width 0.05)
			(type default)
		)
		(layer "Edge.Cuts")
	)
	(gr_line
		(start 94.000066 -16.225012)
		(end 90.65006 -16.225012)
		(stroke
			(width 0.05)
			(type default)
		)
		(layer "Edge.Cuts")
	)
	(gr_line
		(start 95.000064 -26.100024)
		(end 95.000064 -17.22501)
		(stroke
			(width 0.05)
			(type default)
		)
		(layer "Edge.Cuts")
	)
	(gr_arc
		(start 95.000064 -17.22501)
		(mid 94.707171 -16.517905)
		(end 94.000066 -16.225012)
		(stroke
			(width 0.05)
			(type default)
		)
		(layer "Edge.Cuts")
	)
	(segment
		(start 71.92772 -9.412478)
		(end 72.06742 -9.272778)
		(width 0.1397)
		(layer "F.Cu")
		(net "P2E_CPU_SAS_RX_DN0")
	)
	(segment
		(start 70.328282 -15.44066)
		(end 70.328282 -9.747758)
		(width 0.1397)
		(layer "F.Cu")
		(net "P2E_CPU_SAS_RX_DN0")
	)
	(segment
		(start 70.328282 -6.07568)
		(end 69.99986 -5.747258)
		(width 0.1397)
		(layer "F.Cu")
		(net "P2E_CPU_SAS_RX_DN0")
	)
	(segment
		(start 70.000368 -16.649954)
		(end 70.000368 -17.223486)
		(width 0.1397)
		(layer "F.Cu")
		(net "P2E_CPU_SAS_RX_DN0")
	)
	(segment
		(start 70.328282 -8.518398)
		(end 70.328282 -6.07568)
		(width 0.1397)
		(layer "F.Cu")
		(net "P2E_CPU_SAS_RX_DN0")
	)
	(segment
		(start 70.328282 -9.747758)
		(end 70.663562 -9.412478)
		(width 0.1397)
		(layer "F.Cu")
		(net "P2E_CPU_SAS_RX_DN0")
	)
	(segment
		(start 70.000368 -17.223486)
		(end 70.325742 -17.54886)
		(width 0.1397)
		(layer "F.Cu")
		(net "P2E_CPU_SAS_RX_DN0")
	)
	(segment
		(start 70.663562 -9.412478)
		(end 71.92772 -9.412478)
		(width 0.1397)
		(layer "F.Cu")
		(net "P2E_CPU_SAS_RX_DN0")
	)
	(segment
		(start 70.000622 -16.649954)
		(end 70.000368 -16.649954)
		(width 0.1397)
		(layer "F.Cu")
		(net "P2E_CPU_SAS_RX_DN0")
	)
	(segment
		(start 69.99986 -5.747258)
		(end 69.99986 -3.495548)
		(width 0.1397)
		(layer "F.Cu")
		(net "P2E_CPU_SAS_RX_DN0")
	)
	(segment
		(start 70.650862 -17.54886)
		(end 70.879462 -17.32026)
		(width 0.1397)
		(layer "F.Cu")
		(net "P2E_CPU_SAS_RX_DN0")
	)
	(segment
		(start 70.879462 -17.32026)
		(end 70.879462 -15.99184)
		(width 0.1397)
		(layer "F.Cu")
		(net "P2E_CPU_SAS_RX_DN0")
	)
	(segment
		(start 70.879462 -15.99184)
		(end 70.328282 -15.44066)
		(width 0.1397)
		(layer "F.Cu")
		(net "P2E_CPU_SAS_RX_DN0")
	)
	(segment
		(start 70.325742 -17.54886)
		(end 70.650862 -17.54886)
		(width 0.1397)
		(layer "F.Cu")
		(net "P2E_CPU_SAS_RX_DN0")
	)
	(segment
		(start 71.92772 -8.853678)
		(end 70.663562 -8.853678)
		(width 0.1397)
		(layer "F.Cu")
		(net "P2E_CPU_SAS_RX_DN0")
	)
	(segment
		(start 72.06742 -9.272778)
		(end 72.06742 -8.993378)
		(width 0.1397)
		(layer "F.Cu")
		(net "P2E_CPU_SAS_RX_DN0")
	)
	(segment
		(start 72.06742 -8.993378)
		(end 71.92772 -8.853678)
		(width 0.1397)
		(layer "F.Cu")
		(net "P2E_CPU_SAS_RX_DN0")
	)
	(segment
		(start 70.663562 -8.853678)
		(end 70.328282 -8.518398)
		(width 0.1397)
		(layer "F.Cu")
		(net "P2E_CPU_SAS_RX_DN0")
	)
	(segment
		(start 70.671182 -15.29842)
		(end 70.671182 -9.889998)
		(width 0.1397)
		(layer "F.Cu")
		(net "P2E_CPU_SAS_RX_DP0")
	)
	(segment
		(start 71.222362 -17.4625)
		(end 71.222362 -15.8496)
		(width 0.1397)
		(layer "F.Cu")
		(net "P2E_CPU_SAS_RX_DP0")
	)
	(segment
		(start 70.805802 -8.510778)
		(end 70.671182 -8.376158)
		(width 0.1397)
		(layer "F.Cu")
		(net "P2E_CPU_SAS_RX_DP0")
	)
	(segment
		(start 70.671182 -6.07568)
		(end 70.999858 -5.747004)
		(width 0.1397)
		(layer "F.Cu")
		(net "P2E_CPU_SAS_RX_DP0")
	)
	(segment
		(start 72.06996 -9.755378)
		(end 72.41032 -9.415018)
		(width 0.1397)
		(layer "F.Cu")
		(net "P2E_CPU_SAS_RX_DP0")
	)
	(segment
		(start 71.222362 -15.8496)
		(end 70.671182 -15.29842)
		(width 0.1397)
		(layer "F.Cu")
		(net "P2E_CPU_SAS_RX_DP0")
	)
	(segment
		(start 70.999858 -5.747004)
		(end 70.999858 -3.495548)
		(width 0.1397)
		(layer "F.Cu")
		(net "P2E_CPU_SAS_RX_DP0")
	)
	(segment
		(start 70.805802 -9.755378)
		(end 72.06996 -9.755378)
		(width 0.1397)
		(layer "F.Cu")
		(net "P2E_CPU_SAS_RX_DP0")
	)
	(segment
		(start 70.671182 -8.376158)
		(end 70.671182 -6.07568)
		(width 0.1397)
		(layer "F.Cu")
		(net "P2E_CPU_SAS_RX_DP0")
	)
	(segment
		(start 70.999858 -18.650204)
		(end 70.673722 -18.324068)
		(width 0.1397)
		(layer "F.Cu")
		(net "P2E_CPU_SAS_RX_DP0")
	)
	(segment
		(start 72.41032 -9.415018)
		(end 72.41032 -8.851138)
		(width 0.1397)
		(layer "F.Cu")
		(net "P2E_CPU_SAS_RX_DP0")
	)
	(segment
		(start 72.06996 -8.510778)
		(end 70.805802 -8.510778)
		(width 0.1397)
		(layer "F.Cu")
		(net "P2E_CPU_SAS_RX_DP0")
	)
	(segment
		(start 70.671182 -9.889998)
		(end 70.805802 -9.755378)
		(width 0.1397)
		(layer "F.Cu")
		(net "P2E_CPU_SAS_RX_DP0")
	)
	(segment
		(start 70.673722 -18.324068)
		(end 70.673722 -18.01114)
		(width 0.1397)
		(layer "F.Cu")
		(net "P2E_CPU_SAS_RX_DP0")
	)
	(segment
		(start 71.000112 -18.650204)
		(end 70.999858 -18.650204)
		(width 0.1397)
		(layer "F.Cu")
		(net "P2E_CPU_SAS_RX_DP0")
	)
	(segment
		(start 70.673722 -18.01114)
		(end 71.222362 -17.4625)
		(width 0.1397)
		(layer "F.Cu")
		(net "P2E_CPU_SAS_RX_DP0")
	)
	(segment
		(start 72.41032 -8.851138)
		(end 72.06996 -8.510778)
		(width 0.1397)
		(layer "F.Cu")
		(net "P2E_CPU_SAS_RX_DP0")
	)
	(segment
		(start 66.863722 -17.32788)
		(end 66.863722 -16.378682)
		(width 0.1397)
		(layer "F.Cu")
		(net "P2E_CPU_SAS_RX_DN1")
	)
	(segment
		(start 66.2686 -6.09854)
		(end 65.999868 -5.829808)
		(width 0.1397)
		(layer "F.Cu")
		(net "P2E_CPU_SAS_RX_DN1")
	)
	(segment
		(start 63.775082 -10.5029)
		(end 66.2686 -8.009382)
		(width 0.1397)
		(layer "F.Cu")
		(net "P2E_CPU_SAS_RX_DN1")
	)
	(segment
		(start 65.999868 -16.649954)
		(end 65.999868 -17.353026)
		(width 0.1397)
		(layer "F.Cu")
		(net "P2E_CPU_SAS_RX_DN1")
	)
	(segment
		(start 63.775082 -14.725142)
		(end 63.775082 -10.5029)
		(width 0.1397)
		(layer "F.Cu")
		(net "P2E_CPU_SAS_RX_DN1")
	)
	(segment
		(start 66.210942 -17.5641)
		(end 66.627502 -17.5641)
		(width 0.1397)
		(layer "F.Cu")
		(net "P2E_CPU_SAS_RX_DN1")
	)
	(segment
		(start 65.999868 -5.829808)
		(end 65.999868 -3.495548)
		(width 0.1397)
		(layer "F.Cu")
		(net "P2E_CPU_SAS_RX_DN1")
	)
	(segment
		(start 66.2686 -8.009382)
		(end 66.2686 -6.09854)
		(width 0.1397)
		(layer "F.Cu")
		(net "P2E_CPU_SAS_RX_DN1")
	)
	(segment
		(start 65.999868 -17.353026)
		(end 66.210942 -17.5641)
		(width 0.1397)
		(layer "F.Cu")
		(net "P2E_CPU_SAS_RX_DN1")
	)
	(segment
		(start 66.863722 -16.378682)
		(end 66.29908 -15.81404)
		(width 0.1397)
		(layer "F.Cu")
		(net "P2E_CPU_SAS_RX_DN1")
	)
	(segment
		(start 64.86398 -15.81404)
		(end 63.775082 -14.725142)
		(width 0.1397)
		(layer "F.Cu")
		(net "P2E_CPU_SAS_RX_DN1")
	)
	(segment
		(start 66.29908 -15.81404)
		(end 64.86398 -15.81404)
		(width 0.1397)
		(layer "F.Cu")
		(net "P2E_CPU_SAS_RX_DN1")
	)
	(segment
		(start 66.000122 -16.649954)
		(end 65.999868 -16.649954)
		(width 0.1397)
		(layer "F.Cu")
		(net "P2E_CPU_SAS_RX_DN1")
	)
	(segment
		(start 66.627502 -17.5641)
		(end 66.863722 -17.32788)
		(width 0.1397)
		(layer "F.Cu")
		(net "P2E_CPU_SAS_RX_DN1")
	)
	(segment
		(start 66.999358 -18.650204)
		(end 66.6623 -18.313146)
		(width 0.1397)
		(layer "F.Cu")
		(net "P2E_CPU_SAS_RX_DP1")
	)
	(segment
		(start 66.44132 -15.47114)
		(end 65.00622 -15.47114)
		(width 0.1397)
		(layer "F.Cu")
		(net "P2E_CPU_SAS_RX_DP1")
	)
	(segment
		(start 66.6115 -8.151622)
		(end 66.6115 -6.13537)
		(width 0.1397)
		(layer "F.Cu")
		(net "P2E_CPU_SAS_RX_DP1")
	)
	(segment
		(start 66.999612 -18.650204)
		(end 66.999358 -18.650204)
		(width 0.1397)
		(layer "F.Cu")
		(net "P2E_CPU_SAS_RX_DP1")
	)
	(segment
		(start 66.6623 -18.313146)
		(end 66.6623 -18.014442)
		(width 0.1397)
		(layer "F.Cu")
		(net "P2E_CPU_SAS_RX_DP1")
	)
	(segment
		(start 64.117982 -14.582902)
		(end 64.117982 -10.64514)
		(width 0.1397)
		(layer "F.Cu")
		(net "P2E_CPU_SAS_RX_DP1")
	)
	(segment
		(start 66.6623 -18.014442)
		(end 67.206622 -17.47012)
		(width 0.1397)
		(layer "F.Cu")
		(net "P2E_CPU_SAS_RX_DP1")
	)
	(segment
		(start 67.206622 -16.236442)
		(end 66.44132 -15.47114)
		(width 0.1397)
		(layer "F.Cu")
		(net "P2E_CPU_SAS_RX_DP1")
	)
	(segment
		(start 66.6115 -6.13537)
		(end 66.999866 -5.747004)
		(width 0.1397)
		(layer "F.Cu")
		(net "P2E_CPU_SAS_RX_DP1")
	)
	(segment
		(start 65.00622 -15.47114)
		(end 64.117982 -14.582902)
		(width 0.1397)
		(layer "F.Cu")
		(net "P2E_CPU_SAS_RX_DP1")
	)
	(segment
		(start 64.117982 -10.64514)
		(end 66.6115 -8.151622)
		(width 0.1397)
		(layer "F.Cu")
		(net "P2E_CPU_SAS_RX_DP1")
	)
	(segment
		(start 67.206622 -17.47012)
		(end 67.206622 -16.236442)
		(width 0.1397)
		(layer "F.Cu")
		(net "P2E_CPU_SAS_RX_DP1")
	)
	(segment
		(start 66.999866 -5.747004)
		(end 66.999866 -3.495548)
		(width 0.1397)
		(layer "F.Cu")
		(net "P2E_CPU_SAS_RX_DP1")
	)
	(segment
		(start 62.667642 -17.399)
		(end 62.84976 -17.216882)
		(width 0.1397)
		(layer "F.Cu")
		(net "P2E_CPU_SAS_RX_DN2")
	)
	(segment
		(start 62.11062 -13.12037)
		(end 61.78296 -12.79271)
		(width 0.1397)
		(layer "F.Cu")
		(net "P2E_CPU_SAS_RX_DN2")
	)
	(segment
		(start 62.263782 -17.399)
		(end 62.667642 -17.399)
		(width 0.1397)
		(layer "F.Cu")
		(net "P2E_CPU_SAS_RX_DN2")
	)
	(segment
		(start 61.999622 -16.649954)
		(end 61.999368 -16.649954)
		(width 0.1397)
		(layer "F.Cu")
		(net "P2E_CPU_SAS_RX_DN2")
	)
	(segment
		(start 61.999368 -16.649954)
		(end 61.999368 -17.134586)
		(width 0.1397)
		(layer "F.Cu")
		(net "P2E_CPU_SAS_RX_DN2")
	)
	(segment
		(start 61.999368 -17.134586)
		(end 62.263782 -17.399)
		(width 0.1397)
		(layer "F.Cu")
		(net "P2E_CPU_SAS_RX_DN2")
	)
	(segment
		(start 62.11062 -11.87577)
		(end 62.770004 -11.87577)
		(width 0.1397)
		(layer "F.Cu")
		(net "P2E_CPU_SAS_RX_DN2")
	)
	(segment
		(start 62.770004 -13.67917)
		(end 62.909704 -13.53947)
		(width 0.1397)
		(layer "F.Cu")
		(net "P2E_CPU_SAS_RX_DN2")
	)
	(segment
		(start 62.770004 -11.87577)
		(end 62.909704 -11.73607)
		(width 0.1397)
		(layer "F.Cu")
		(net "P2E_CPU_SAS_RX_DN2")
	)
	(segment
		(start 62.328552 -10.875518)
		(end 62.328552 -6.07568)
		(width 0.1397)
		(layer "F.Cu")
		(net "P2E_CPU_SAS_RX_DN2")
	)
	(segment
		(start 61.7474 -14.58341)
		(end 61.7474 -14.01953)
		(width 0.1397)
		(layer "F.Cu")
		(net "P2E_CPU_SAS_RX_DN2")
	)
	(segment
		(start 62.08776 -13.67917)
		(end 62.770004 -13.67917)
		(width 0.1397)
		(layer "F.Cu")
		(net "P2E_CPU_SAS_RX_DN2")
	)
	(segment
		(start 62.84976 -17.216882)
		(end 62.84976 -15.68577)
		(width 0.1397)
		(layer "F.Cu")
		(net "P2E_CPU_SAS_RX_DN2")
	)
	(segment
		(start 62.909704 -11.73607)
		(end 62.909704 -11.45667)
		(width 0.1397)
		(layer "F.Cu")
		(net "P2E_CPU_SAS_RX_DN2")
	)
	(segment
		(start 61.78296 -12.20343)
		(end 62.11062 -11.87577)
		(width 0.1397)
		(layer "F.Cu")
		(net "P2E_CPU_SAS_RX_DN2")
	)
	(segment
		(start 62.909704 -11.45667)
		(end 62.328552 -10.875518)
		(width 0.1397)
		(layer "F.Cu")
		(net "P2E_CPU_SAS_RX_DN2")
	)
	(segment
		(start 62.909704 -13.26007)
		(end 62.770004 -13.12037)
		(width 0.1397)
		(layer "F.Cu")
		(net "P2E_CPU_SAS_RX_DN2")
	)
	(segment
		(start 61.78296 -12.79271)
		(end 61.78296 -12.20343)
		(width 0.1397)
		(layer "F.Cu")
		(net "P2E_CPU_SAS_RX_DN2")
	)
	(segment
		(start 62.770004 -13.12037)
		(end 62.11062 -13.12037)
		(width 0.1397)
		(layer "F.Cu")
		(net "P2E_CPU_SAS_RX_DN2")
	)
	(segment
		(start 61.999876 -5.747004)
		(end 61.999876 -3.495548)
		(width 0.1397)
		(layer "F.Cu")
		(net "P2E_CPU_SAS_RX_DN2")
	)
	(segment
		(start 62.84976 -15.68577)
		(end 61.7474 -14.58341)
		(width 0.1397)
		(layer "F.Cu")
		(net "P2E_CPU_SAS_RX_DN2")
	)
	(segment
		(start 61.7474 -14.01953)
		(end 62.08776 -13.67917)
		(width 0.1397)
		(layer "F.Cu")
		(net "P2E_CPU_SAS_RX_DN2")
	)
	(segment
		(start 62.909704 -13.53947)
		(end 62.909704 -13.26007)
		(width 0.1397)
		(layer "F.Cu")
		(net "P2E_CPU_SAS_RX_DN2")
	)
	(segment
		(start 62.328552 -6.07568)
		(end 61.999876 -5.747004)
		(width 0.1397)
		(layer "F.Cu")
		(net "P2E_CPU_SAS_RX_DN2")
	)
	(segment
		(start 62.23 -14.02207)
		(end 62.912244 -14.02207)
		(width 0.1397)
		(layer "F.Cu")
		(net "P2E_CPU_SAS_RX_DP2")
	)
	(segment
		(start 62.912244 -12.21867)
		(end 63.252604 -11.87831)
		(width 0.1397)
		(layer "F.Cu")
		(net "P2E_CPU_SAS_RX_DP2")
	)
	(segment
		(start 62.671452 -6.07568)
		(end 62.999874 -5.747258)
		(width 0.1397)
		(layer "F.Cu")
		(net "P2E_CPU_SAS_RX_DP2")
	)
	(segment
		(start 62.25286 -12.21867)
		(end 62.912244 -12.21867)
		(width 0.1397)
		(layer "F.Cu")
		(net "P2E_CPU_SAS_RX_DP2")
	)
	(segment
		(start 63.19266 -17.359122)
		(end 63.19266 -15.54353)
		(width 0.1397)
		(layer "F.Cu")
		(net "P2E_CPU_SAS_RX_DP2")
	)
	(segment
		(start 63.252604 -13.68171)
		(end 63.252604 -13.11783)
		(width 0.1397)
		(layer "F.Cu")
		(net "P2E_CPU_SAS_RX_DP2")
	)
	(segment
		(start 62.0903 -14.44117)
		(end 62.0903 -14.16177)
		(width 0.1397)
		(layer "F.Cu")
		(net "P2E_CPU_SAS_RX_DP2")
	)
	(segment
		(start 63.19266 -15.54353)
		(end 62.0903 -14.44117)
		(width 0.1397)
		(layer "F.Cu")
		(net "P2E_CPU_SAS_RX_DP2")
	)
	(segment
		(start 62.25286 -12.77747)
		(end 62.12586 -12.65047)
		(width 0.1397)
		(layer "F.Cu")
		(net "P2E_CPU_SAS_RX_DP2")
	)
	(segment
		(start 62.912244 -14.02207)
		(end 63.252604 -13.68171)
		(width 0.1397)
		(layer "F.Cu")
		(net "P2E_CPU_SAS_RX_DP2")
	)
	(segment
		(start 62.999874 -5.747258)
		(end 62.999874 -3.495548)
		(width 0.1397)
		(layer "F.Cu")
		(net "P2E_CPU_SAS_RX_DP2")
	)
	(segment
		(start 63.252604 -13.11783)
		(end 62.912244 -12.77747)
		(width 0.1397)
		(layer "F.Cu")
		(net "P2E_CPU_SAS_RX_DP2")
	)
	(segment
		(start 63.000128 -17.551654)
		(end 63.19266 -17.359122)
		(width 0.1397)
		(layer "F.Cu")
		(net "P2E_CPU_SAS_RX_DP2")
	)
	(segment
		(start 62.912244 -12.77747)
		(end 62.25286 -12.77747)
		(width 0.1397)
		(layer "F.Cu")
		(net "P2E_CPU_SAS_RX_DP2")
	)
	(segment
		(start 62.671452 -10.733278)
		(end 62.671452 -6.07568)
		(width 0.1397)
		(layer "F.Cu")
		(net "P2E_CPU_SAS_RX_DP2")
	)
	(segment
		(start 62.0903 -14.16177)
		(end 62.23 -14.02207)
		(width 0.1397)
		(layer "F.Cu")
		(net "P2E_CPU_SAS_RX_DP2")
	)
	(segment
		(start 62.12586 -12.65047)
		(end 62.12586 -12.34567)
		(width 0.1397)
		(layer "F.Cu")
		(net "P2E_CPU_SAS_RX_DP2")
	)
	(segment
		(start 63.252604 -11.87831)
		(end 63.252604 -11.31443)
		(width 0.1397)
		(layer "F.Cu")
		(net "P2E_CPU_SAS_RX_DP2")
	)
	(segment
		(start 62.12586 -12.34567)
		(end 62.25286 -12.21867)
		(width 0.1397)
		(layer "F.Cu")
		(net "P2E_CPU_SAS_RX_DP2")
	)
	(segment
		(start 63.252604 -11.31443)
		(end 62.671452 -10.733278)
		(width 0.1397)
		(layer "F.Cu")
		(net "P2E_CPU_SAS_RX_DP2")
	)
	(segment
		(start 63.000128 -18.650204)
		(end 63.000128 -17.551654)
		(width 0.1397)
		(layer "F.Cu")
		(net "P2E_CPU_SAS_RX_DP2")
	)
	(segment
		(start 63.000382 -18.650204)
		(end 63.000128 -18.650204)
		(width 0.1397)
		(layer "F.Cu")
		(net "P2E_CPU_SAS_RX_DP2")
	)
	(segment
		(start 57.912 -11.41476)
		(end 57.912 -10.85088)
		(width 0.1397)
		(layer "F.Cu")
		(net "P2E_CPU_SAS_RX_DN3")
	)
	(segment
		(start 58.60542 -10.51052)
		(end 58.74512 -10.37082)
		(width 0.1397)
		(layer "F.Cu")
		(net "P2E_CPU_SAS_RX_DN3")
	)
	(segment
		(start 58.74512 -10.09142)
		(end 58.32856 -9.67486)
		(width 0.1397)
		(layer "F.Cu")
		(net "P2E_CPU_SAS_RX_DN3")
	)
	(segment
		(start 58.000392 -16.649954)
		(end 58.000138 -16.649954)
		(width 0.1397)
		(layer "F.Cu")
		(net "P2E_CPU_SAS_RX_DN3")
	)
	(segment
		(start 58.861452 -17.20596)
		(end 58.861452 -16.034512)
		(width 0.1397)
		(layer "F.Cu")
		(net "P2E_CPU_SAS_RX_DN3")
	)
	(segment
		(start 58.74512 -11.89482)
		(end 58.60542 -11.75512)
		(width 0.1397)
		(layer "F.Cu")
		(net "P2E_CPU_SAS_RX_DN3")
	)
	(segment
		(start 58.861452 -16.034512)
		(end 57.912 -15.08506)
		(width 0.1397)
		(layer "F.Cu")
		(net "P2E_CPU_SAS_RX_DN3")
	)
	(segment
		(start 57.912 -12.65428)
		(end 58.25236 -12.31392)
		(width 0.1397)
		(layer "F.Cu")
		(net "P2E_CPU_SAS_RX_DN3")
	)
	(segment
		(start 58.25236 -11.75512)
		(end 57.912 -11.41476)
		(width 0.1397)
		(layer "F.Cu")
		(net "P2E_CPU_SAS_RX_DN3")
	)
	(segment
		(start 57.912 -13.21816)
		(end 57.912 -12.65428)
		(width 0.1397)
		(layer "F.Cu")
		(net "P2E_CPU_SAS_RX_DN3")
	)
	(segment
		(start 58.74512 -13.69822)
		(end 58.60542 -13.55852)
		(width 0.1397)
		(layer "F.Cu")
		(net "P2E_CPU_SAS_RX_DN3")
	)
	(segment
		(start 58.60542 -12.31392)
		(end 58.74512 -12.17422)
		(width 0.1397)
		(layer "F.Cu")
		(net "P2E_CPU_SAS_RX_DN3")
	)
	(segment
		(start 58.000138 -16.649954)
		(end 58.000138 -17.134586)
		(width 0.1397)
		(layer "F.Cu")
		(net "P2E_CPU_SAS_RX_DN3")
	)
	(segment
		(start 57.912 -10.85088)
		(end 58.25236 -10.51052)
		(width 0.1397)
		(layer "F.Cu")
		(net "P2E_CPU_SAS_RX_DN3")
	)
	(segment
		(start 58.668412 -17.399)
		(end 58.861452 -17.20596)
		(width 0.1397)
		(layer "F.Cu")
		(net "P2E_CPU_SAS_RX_DN3")
	)
	(segment
		(start 58.25236 -14.11732)
		(end 58.60542 -14.11732)
		(width 0.1397)
		(layer "F.Cu")
		(net "P2E_CPU_SAS_RX_DN3")
	)
	(segment
		(start 58.60542 -13.55852)
		(end 58.25236 -13.55852)
		(width 0.1397)
		(layer "F.Cu")
		(net "P2E_CPU_SAS_RX_DN3")
	)
	(segment
		(start 58.74512 -12.17422)
		(end 58.74512 -11.89482)
		(width 0.1397)
		(layer "F.Cu")
		(net "P2E_CPU_SAS_RX_DN3")
	)
	(segment
		(start 58.60542 -11.75512)
		(end 58.25236 -11.75512)
		(width 0.1397)
		(layer "F.Cu")
		(net "P2E_CPU_SAS_RX_DN3")
	)
	(segment
		(start 58.264552 -17.399)
		(end 58.668412 -17.399)
		(width 0.1397)
		(layer "F.Cu")
		(net "P2E_CPU_SAS_RX_DN3")
	)
	(segment
		(start 57.912 -14.45768)
		(end 58.25236 -14.11732)
		(width 0.1397)
		(layer "F.Cu")
		(net "P2E_CPU_SAS_RX_DN3")
	)
	(segment
		(start 58.25236 -10.51052)
		(end 58.60542 -10.51052)
		(width 0.1397)
		(layer "F.Cu")
		(net "P2E_CPU_SAS_RX_DN3")
	)
	(segment
		(start 57.999884 -5.747004)
		(end 57.999884 -3.495548)
		(width 0.1397)
		(layer "F.Cu")
		(net "P2E_CPU_SAS_RX_DN3")
	)
	(segment
		(start 58.60542 -14.11732)
		(end 58.74512 -13.97762)
		(width 0.1397)
		(layer "F.Cu")
		(net "P2E_CPU_SAS_RX_DN3")
	)
	(segment
		(start 58.25236 -13.55852)
		(end 57.912 -13.21816)
		(width 0.1397)
		(layer "F.Cu")
		(net "P2E_CPU_SAS_RX_DN3")
	)
	(segment
		(start 58.32856 -6.07568)
		(end 57.999884 -5.747004)
		(width 0.1397)
		(layer "F.Cu")
		(net "P2E_CPU_SAS_RX_DN3")
	)
	(segment
		(start 58.25236 -12.31392)
		(end 58.60542 -12.31392)
		(width 0.1397)
		(layer "F.Cu")
		(net "P2E_CPU_SAS_RX_DN3")
	)
	(segment
		(start 58.000138 -17.134586)
		(end 58.264552 -17.399)
		(width 0.1397)
		(layer "F.Cu")
		(net "P2E_CPU_SAS_RX_DN3")
	)
	(segment
		(start 58.74512 -10.37082)
		(end 58.74512 -10.09142)
		(width 0.1397)
		(layer "F.Cu")
		(net "P2E_CPU_SAS_RX_DN3")
	)
	(segment
		(start 58.74512 -13.97762)
		(end 58.74512 -13.69822)
		(width 0.1397)
		(layer "F.Cu")
		(net "P2E_CPU_SAS_RX_DN3")
	)
	(segment
		(start 57.912 -15.08506)
		(end 57.912 -14.45768)
		(width 0.1397)
		(layer "F.Cu")
		(net "P2E_CPU_SAS_RX_DN3")
	)
	(segment
		(start 58.32856 -9.67486)
		(end 58.32856 -6.07568)
		(width 0.1397)
		(layer "F.Cu")
		(net "P2E_CPU_SAS_RX_DN3")
	)
	(segment
		(start 58.2549 -13.07592)
		(end 58.2549 -12.79652)
		(width 0.1397)
		(layer "F.Cu")
		(net "P2E_CPU_SAS_RX_DP3")
	)
	(segment
		(start 59.08802 -14.11986)
		(end 59.08802 -13.55598)
		(width 0.1397)
		(layer "F.Cu")
		(net "P2E_CPU_SAS_RX_DP3")
	)
	(segment
		(start 58.999882 -18.650204)
		(end 58.999628 -18.650204)
		(width 0.1397)
		(layer "F.Cu")
		(net "P2E_CPU_SAS_RX_DP3")
	)
	(segment
		(start 58.3946 -14.46022)
		(end 58.74766 -14.46022)
		(width 0.1397)
		(layer "F.Cu")
		(net "P2E_CPU_SAS_RX_DP3")
	)
	(segment
		(start 59.08802 -10.51306)
		(end 59.08802 -9.94918)
		(width 0.1397)
		(layer "F.Cu")
		(net "P2E_CPU_SAS_RX_DP3")
	)
	(segment
		(start 59.08802 -9.94918)
		(end 58.67146 -9.53262)
		(width 0.1397)
		(layer "F.Cu")
		(net "P2E_CPU_SAS_RX_DP3")
	)
	(segment
		(start 58.2549 -10.99312)
		(end 58.3946 -10.85342)
		(width 0.1397)
		(layer "F.Cu")
		(net "P2E_CPU_SAS_RX_DP3")
	)
	(segment
		(start 58.3946 -10.85342)
		(end 58.74766 -10.85342)
		(width 0.1397)
		(layer "F.Cu")
		(net "P2E_CPU_SAS_RX_DP3")
	)
	(segment
		(start 58.67146 -6.07568)
		(end 58.999882 -5.747258)
		(width 0.1397)
		(layer "F.Cu")
		(net "P2E_CPU_SAS_RX_DP3")
	)
	(segment
		(start 58.67146 -9.53262)
		(end 58.67146 -6.07568)
		(width 0.1397)
		(layer "F.Cu")
		(net "P2E_CPU_SAS_RX_DP3")
	)
	(segment
		(start 58.74766 -14.46022)
		(end 59.08802 -14.11986)
		(width 0.1397)
		(layer "F.Cu")
		(net "P2E_CPU_SAS_RX_DP3")
	)
	(segment
		(start 58.74766 -11.41222)
		(end 58.3946 -11.41222)
		(width 0.1397)
		(layer "F.Cu")
		(net "P2E_CPU_SAS_RX_DP3")
	)
	(segment
		(start 58.3946 -11.41222)
		(end 58.2549 -11.27252)
		(width 0.1397)
		(layer "F.Cu")
		(net "P2E_CPU_SAS_RX_DP3")
	)
	(segment
		(start 58.999628 -17.552924)
		(end 59.204352 -17.3482)
		(width 0.1397)
		(layer "F.Cu")
		(net "P2E_CPU_SAS_RX_DP3")
	)
	(segment
		(start 58.999628 -18.650204)
		(end 58.999628 -17.552924)
		(width 0.1397)
		(layer "F.Cu")
		(net "P2E_CPU_SAS_RX_DP3")
	)
	(segment
		(start 58.2549 -14.94282)
		(end 58.2549 -14.59992)
		(width 0.1397)
		(layer "F.Cu")
		(net "P2E_CPU_SAS_RX_DP3")
	)
	(segment
		(start 59.204352 -17.3482)
		(end 59.204352 -15.892272)
		(width 0.1397)
		(layer "F.Cu")
		(net "P2E_CPU_SAS_RX_DP3")
	)
	(segment
		(start 59.204352 -15.892272)
		(end 58.2549 -14.94282)
		(width 0.1397)
		(layer "F.Cu")
		(net "P2E_CPU_SAS_RX_DP3")
	)
	(segment
		(start 58.2549 -14.59992)
		(end 58.3946 -14.46022)
		(width 0.1397)
		(layer "F.Cu")
		(net "P2E_CPU_SAS_RX_DP3")
	)
	(segment
		(start 58.999882 -5.747258)
		(end 58.999882 -3.495548)
		(width 0.1397)
		(layer "F.Cu")
		(net "P2E_CPU_SAS_RX_DP3")
	)
	(segment
		(start 58.74766 -10.85342)
		(end 59.08802 -10.51306)
		(width 0.1397)
		(layer "F.Cu")
		(net "P2E_CPU_SAS_RX_DP3")
	)
	(segment
		(start 59.08802 -13.55598)
		(end 58.74766 -13.21562)
		(width 0.1397)
		(layer "F.Cu")
		(net "P2E_CPU_SAS_RX_DP3")
	)
	(segment
		(start 58.3946 -12.65682)
		(end 58.74766 -12.65682)
		(width 0.1397)
		(layer "F.Cu")
		(net "P2E_CPU_SAS_RX_DP3")
	)
	(segment
		(start 58.74766 -13.21562)
		(end 58.3946 -13.21562)
		(width 0.1397)
		(layer "F.Cu")
		(net "P2E_CPU_SAS_RX_DP3")
	)
	(segment
		(start 59.08802 -11.75258)
		(end 58.74766 -11.41222)
		(width 0.1397)
		(layer "F.Cu")
		(net "P2E_CPU_SAS_RX_DP3")
	)
	(segment
		(start 58.74766 -12.65682)
		(end 59.08802 -12.31646)
		(width 0.1397)
		(layer "F.Cu")
		(net "P2E_CPU_SAS_RX_DP3")
	)
	(segment
		(start 58.2549 -11.27252)
		(end 58.2549 -10.99312)
		(width 0.1397)
		(layer "F.Cu")
		(net "P2E_CPU_SAS_RX_DP3")
	)
	(segment
		(start 59.08802 -12.31646)
		(end 59.08802 -11.75258)
		(width 0.1397)
		(layer "F.Cu")
		(net "P2E_CPU_SAS_RX_DP3")
	)
	(segment
		(start 58.2549 -12.79652)
		(end 58.3946 -12.65682)
		(width 0.1397)
		(layer "F.Cu")
		(net "P2E_CPU_SAS_RX_DP3")
	)
	(segment
		(start 58.3946 -13.21562)
		(end 58.2549 -13.07592)
		(width 0.1397)
		(layer "F.Cu")
		(net "P2E_CPU_SAS_RX_DP3")
	)
	(segment
		(start 54.290722 -17.41424)
		(end 54.652672 -17.41424)
		(width 0.1397)
		(layer "F.Cu")
		(net "SATA2_RX_C_DN0")
	)
	(segment
		(start 53.999892 -5.747004)
		(end 53.999892 -3.495548)
		(width 0.1397)
		(layer "F.Cu")
		(net "SATA2_RX_C_DN0")
	)
	(segment
		(start 54.652672 -17.41424)
		(end 54.860952 -17.20596)
		(width 0.1397)
		(layer "F.Cu")
		(net "SATA2_RX_C_DN0")
	)
	(segment
		(start 54.860952 -17.20596)
		(end 54.860952 -16.217392)
		(width 0.1397)
		(layer "F.Cu")
		(net "SATA2_RX_C_DN0")
	)
	(segment
		(start 53.999638 -17.123156)
		(end 54.290722 -17.41424)
		(width 0.1397)
		(layer "F.Cu")
		(net "SATA2_RX_C_DN0")
	)
	(segment
		(start 53.999892 -16.649954)
		(end 53.999638 -16.649954)
		(width 0.1397)
		(layer "F.Cu")
		(net "SATA2_RX_C_DN0")
	)
	(segment
		(start 54.328822 -15.685262)
		(end 54.328822 -6.075934)
		(width 0.1397)
		(layer "F.Cu")
		(net "SATA2_RX_C_DN0")
	)
	(segment
		(start 54.860952 -16.217392)
		(end 54.328822 -15.685262)
		(width 0.1397)
		(layer "F.Cu")
		(net "SATA2_RX_C_DN0")
	)
	(segment
		(start 54.328822 -6.075934)
		(end 53.999892 -5.747004)
		(width 0.1397)
		(layer "F.Cu")
		(net "SATA2_RX_C_DN0")
	)
	(segment
		(start 53.999638 -16.649954)
		(end 53.999638 -17.123156)
		(width 0.1397)
		(layer "F.Cu")
		(net "SATA2_RX_C_DN0")
	)
	(segment
		(start 54.671722 -6.075426)
		(end 54.99989 -5.747258)
		(width 0.1397)
		(layer "F.Cu")
		(net "SATA2_RX_C_DP0")
	)
	(segment
		(start 55.203852 -17.3482)
		(end 55.203852 -16.075152)
		(width 0.1397)
		(layer "F.Cu")
		(net "SATA2_RX_C_DP0")
	)
	(segment
		(start 55.000398 -17.551654)
		(end 55.203852 -17.3482)
		(width 0.1397)
		(layer "F.Cu")
		(net "SATA2_RX_C_DP0")
	)
	(segment
		(start 55.000398 -18.650204)
		(end 55.000398 -17.551654)
		(width 0.1397)
		(layer "F.Cu")
		(net "SATA2_RX_C_DP0")
	)
	(segment
		(start 55.203852 -16.075152)
		(end 54.671722 -15.543022)
		(width 0.1397)
		(layer "F.Cu")
		(net "SATA2_RX_C_DP0")
	)
	(segment
		(start 54.99989 -5.747258)
		(end 54.99989 -3.495548)
		(width 0.1397)
		(layer "F.Cu")
		(net "SATA2_RX_C_DP0")
	)
	(segment
		(start 54.671722 -15.543022)
		(end 54.671722 -6.075426)
		(width 0.1397)
		(layer "F.Cu")
		(net "SATA2_RX_C_DP0")
	)
	(segment
		(start 55.000652 -18.650204)
		(end 55.000398 -18.650204)
		(width 0.1397)
		(layer "F.Cu")
		(net "SATA2_RX_C_DP0")
	)
	(segment
		(start 46.000162 -16.649954)
		(end 46.000162 -16.6497)
		(width 0.10795)
		(layer "F.Cu")
		(net "GBE_SMBALRT_R#")
	)
	(segment
		(start 45.999908 -5.747004)
		(end 45.999908 -3.495548)
		(width 0.10795)
		(layer "F.Cu")
		(net "GBE_SMBALRT_R#")
	)
	(segment
		(start 46.328584 -16.321278)
		(end 46.328584 -6.07568)
		(width 0.10795)
		(layer "F.Cu")
		(net "GBE_SMBALRT_R#")
	)
	(segment
		(start 46.328584 -6.07568)
		(end 45.999908 -5.747004)
		(width 0.10795)
		(layer "F.Cu")
		(net "GBE_SMBALRT_R#")
	)
	(segment
		(start 46.000162 -16.6497)
		(end 46.328584 -16.321278)
		(width 0.10795)
		(layer "F.Cu")
		(net "GBE_SMBALRT_R#")
	)
	(segment
		(start 46.671484 -14.477492)
		(end 46.671484 -6.07568)
		(width 0.127)
		(layer "F.Cu")
		(net "PCIE_RSVD_A41")
	)
	(segment
		(start 46.999906 -5.747258)
		(end 46.999906 -3.495548)
		(width 0.127)
		(layer "F.Cu")
		(net "PCIE_RSVD_A41")
	)
	(segment
		(start 46.999398 -14.805406)
		(end 46.671484 -14.477492)
		(width 0.127)
		(layer "F.Cu")
		(net "PCIE_RSVD_A41")
	)
	(segment
		(start 46.999398 -18.650204)
		(end 46.999398 -14.805406)
		(width 0.127)
		(layer "F.Cu")
		(net "PCIE_RSVD_A41")
	)
	(segment
		(start 46.999652 -18.650204)
		(end 46.999398 -18.650204)
		(width 0.127)
		(layer "F.Cu")
		(net "PCIE_RSVD_A41")
	)
	(segment
		(start 46.671484 -6.07568)
		(end 46.999906 -5.747258)
		(width 0.127)
		(layer "F.Cu")
		(net "PCIE_RSVD_A41")
	)
	(segment
		(start 43.203622 -15.01013)
		(end 42.671492 -14.478)
		(width 0.1397)
		(layer "F.Cu")
		(net "CPU_GBE_RX_C_DP0")
	)
	(segment
		(start 42.671492 -6.07568)
		(end 42.999914 -5.747258)
		(width 0.1397)
		(layer "F.Cu")
		(net "CPU_GBE_RX_C_DP0")
	)
	(segment
		(start 43.000422 -18.650204)
		(end 43.000168 -18.650204)
		(width 0.1397)
		(layer "F.Cu")
		(net "CPU_GBE_RX_C_DP0")
	)
	(segment
		(start 43.000168 -18.650204)
		(end 43.000168 -17.551654)
		(width 0.1397)
		(layer "F.Cu")
		(net "CPU_GBE_RX_C_DP0")
	)
	(segment
		(start 43.203622 -17.3482)
		(end 43.203622 -15.01013)
		(width 0.1397)
		(layer "F.Cu")
		(net "CPU_GBE_RX_C_DP0")
	)
	(segment
		(start 43.000168 -17.551654)
		(end 43.203622 -17.3482)
		(width 0.1397)
		(layer "F.Cu")
		(net "CPU_GBE_RX_C_DP0")
	)
	(segment
		(start 42.671492 -14.478)
		(end 42.671492 -6.07568)
		(width 0.1397)
		(layer "F.Cu")
		(net "CPU_GBE_RX_C_DP0")
	)
	(segment
		(start 42.999914 -5.747258)
		(end 42.999914 -3.495548)
		(width 0.1397)
		(layer "F.Cu")
		(net "CPU_GBE_RX_C_DP0")
	)
	(segment
		(start 41.999408 -16.649954)
		(end 41.999408 -17.134586)
		(width 0.1397)
		(layer "F.Cu")
		(net "CPU_GBE_RX_C_DN0")
	)
	(segment
		(start 42.667682 -17.399)
		(end 42.860722 -17.20596)
		(width 0.1397)
		(layer "F.Cu")
		(net "CPU_GBE_RX_C_DN0")
	)
	(segment
		(start 42.328592 -6.07568)
		(end 41.999916 -5.747004)
		(width 0.1397)
		(layer "F.Cu")
		(net "CPU_GBE_RX_C_DN0")
	)
	(segment
		(start 42.328592 -14.619732)
		(end 42.328592 -6.07568)
		(width 0.1397)
		(layer "F.Cu")
		(net "CPU_GBE_RX_C_DN0")
	)
	(segment
		(start 42.860722 -15.15237)
		(end 42.328338 -14.619986)
		(width 0.1397)
		(layer "F.Cu")
		(net "CPU_GBE_RX_C_DN0")
	)
	(segment
		(start 42.328338 -14.619986)
		(end 42.328592 -14.619732)
		(width 0.1397)
		(layer "F.Cu")
		(net "CPU_GBE_RX_C_DN0")
	)
	(segment
		(start 41.999916 -5.747004)
		(end 41.999916 -3.495548)
		(width 0.1397)
		(layer "F.Cu")
		(net "CPU_GBE_RX_C_DN0")
	)
	(segment
		(start 41.999408 -17.134586)
		(end 42.263822 -17.399)
		(width 0.1397)
		(layer "F.Cu")
		(net "CPU_GBE_RX_C_DN0")
	)
	(segment
		(start 42.860722 -17.20596)
		(end 42.860722 -15.15237)
		(width 0.1397)
		(layer "F.Cu")
		(net "CPU_GBE_RX_C_DN0")
	)
	(segment
		(start 41.999662 -16.649954)
		(end 41.999408 -16.649954)
		(width 0.1397)
		(layer "F.Cu")
		(net "CPU_GBE_RX_C_DN0")
	)
	(segment
		(start 42.263822 -17.399)
		(end 42.667682 -17.399)
		(width 0.1397)
		(layer "F.Cu")
		(net "CPU_GBE_RX_C_DN0")
	)
	(segment
		(start 38.6588 -13.235178)
		(end 38.7985 -13.095478)
		(width 0.1397)
		(layer "F.Cu")
		(net "P2E_CPU_SAS_RX_DN4")
	)
	(segment
		(start 38.68166 -10.872978)
		(end 38.19906 -10.872978)
		(width 0.1397)
		(layer "F.Cu")
		(net "P2E_CPU_SAS_RX_DN4")
	)
	(segment
		(start 38.19906 -10.872978)
		(end 37.8587 -10.532618)
		(width 0.1397)
		(layer "F.Cu")
		(net "P2E_CPU_SAS_RX_DN4")
	)
	(segment
		(start 38.668452 -17.399)
		(end 38.861492 -17.20596)
		(width 0.1397)
		(layer "F.Cu")
		(net "P2E_CPU_SAS_RX_DN4")
	)
	(segment
		(start 38.7985 -12.816078)
		(end 38.6588 -12.676378)
		(width 0.1397)
		(layer "F.Cu")
		(net "P2E_CPU_SAS_RX_DN4")
	)
	(segment
		(start 38.19906 -11.431778)
		(end 38.68166 -11.431778)
		(width 0.1397)
		(layer "F.Cu")
		(net "P2E_CPU_SAS_RX_DN4")
	)
	(segment
		(start 37.8587 -9.968738)
		(end 38.3286 -9.498838)
		(width 0.1397)
		(layer "F.Cu")
		(net "P2E_CPU_SAS_RX_DN4")
	)
	(segment
		(start 38.000432 -16.649954)
		(end 38.000178 -16.649954)
		(width 0.1397)
		(layer "F.Cu")
		(net "P2E_CPU_SAS_RX_DN4")
	)
	(segment
		(start 38.19906 -12.676378)
		(end 37.8587 -12.336018)
		(width 0.1397)
		(layer "F.Cu")
		(net "P2E_CPU_SAS_RX_DN4")
	)
	(segment
		(start 38.19906 -13.235178)
		(end 38.6588 -13.235178)
		(width 0.1397)
		(layer "F.Cu")
		(net "P2E_CPU_SAS_RX_DN4")
	)
	(segment
		(start 38.3286 -9.498838)
		(end 38.3286 -6.07568)
		(width 0.1397)
		(layer "F.Cu")
		(net "P2E_CPU_SAS_RX_DN4")
	)
	(segment
		(start 37.999924 -5.747004)
		(end 37.999924 -3.495548)
		(width 0.1397)
		(layer "F.Cu")
		(net "P2E_CPU_SAS_RX_DN4")
	)
	(segment
		(start 37.8587 -14.149578)
		(end 37.8587 -13.575538)
		(width 0.1397)
		(layer "F.Cu")
		(net "P2E_CPU_SAS_RX_DN4")
	)
	(segment
		(start 37.8587 -10.532618)
		(end 37.8587 -9.968738)
		(width 0.1397)
		(layer "F.Cu")
		(net "P2E_CPU_SAS_RX_DN4")
	)
	(segment
		(start 38.861492 -15.15237)
		(end 37.8587 -14.149578)
		(width 0.1397)
		(layer "F.Cu")
		(net "P2E_CPU_SAS_RX_DN4")
	)
	(segment
		(start 38.3286 -6.07568)
		(end 37.999924 -5.747004)
		(width 0.1397)
		(layer "F.Cu")
		(net "P2E_CPU_SAS_RX_DN4")
	)
	(segment
		(start 38.861492 -17.20596)
		(end 38.861492 -15.15237)
		(width 0.1397)
		(layer "F.Cu")
		(net "P2E_CPU_SAS_RX_DN4")
	)
	(segment
		(start 38.80866 -11.304778)
		(end 38.80866 -10.999978)
		(width 0.1397)
		(layer "F.Cu")
		(net "P2E_CPU_SAS_RX_DN4")
	)
	(segment
		(start 38.80866 -10.999978)
		(end 38.68166 -10.872978)
		(width 0.1397)
		(layer "F.Cu")
		(net "P2E_CPU_SAS_RX_DN4")
	)
	(segment
		(start 38.6588 -12.676378)
		(end 38.19906 -12.676378)
		(width 0.1397)
		(layer "F.Cu")
		(net "P2E_CPU_SAS_RX_DN4")
	)
	(segment
		(start 38.000178 -16.649954)
		(end 38.000178 -17.134586)
		(width 0.1397)
		(layer "F.Cu")
		(net "P2E_CPU_SAS_RX_DN4")
	)
	(segment
		(start 37.8587 -12.336018)
		(end 37.8587 -11.772138)
		(width 0.1397)
		(layer "F.Cu")
		(net "P2E_CPU_SAS_RX_DN4")
	)
	(segment
		(start 37.8587 -13.575538)
		(end 38.19906 -13.235178)
		(width 0.1397)
		(layer "F.Cu")
		(net "P2E_CPU_SAS_RX_DN4")
	)
	(segment
		(start 38.000178 -17.134586)
		(end 38.264592 -17.399)
		(width 0.1397)
		(layer "F.Cu")
		(net "P2E_CPU_SAS_RX_DN4")
	)
	(segment
		(start 37.8587 -11.772138)
		(end 38.19906 -11.431778)
		(width 0.1397)
		(layer "F.Cu")
		(net "P2E_CPU_SAS_RX_DN4")
	)
	(segment
		(start 38.68166 -11.431778)
		(end 38.80866 -11.304778)
		(width 0.1397)
		(layer "F.Cu")
		(net "P2E_CPU_SAS_RX_DN4")
	)
	(segment
		(start 38.264592 -17.399)
		(end 38.668452 -17.399)
		(width 0.1397)
		(layer "F.Cu")
		(net "P2E_CPU_SAS_RX_DN4")
	)
	(segment
		(start 38.7985 -13.095478)
		(end 38.7985 -12.816078)
		(width 0.1397)
		(layer "F.Cu")
		(net "P2E_CPU_SAS_RX_DN4")
	)
	(segment
		(start 38.2016 -12.193778)
		(end 38.2016 -11.914378)
		(width 0.1397)
		(layer "F.Cu")
		(net "P2E_CPU_SAS_RX_DP4")
	)
	(segment
		(start 39.204392 -15.01013)
		(end 38.2016 -14.007338)
		(width 0.1397)
		(layer "F.Cu")
		(net "P2E_CPU_SAS_RX_DP4")
	)
	(segment
		(start 38.2016 -11.914378)
		(end 38.3413 -11.774678)
		(width 0.1397)
		(layer "F.Cu")
		(net "P2E_CPU_SAS_RX_DP4")
	)
	(segment
		(start 39.15156 -10.857738)
		(end 38.8239 -10.530078)
		(width 0.1397)
		(layer "F.Cu")
		(net "P2E_CPU_SAS_RX_DP4")
	)
	(segment
		(start 39.204392 -17.3482)
		(end 39.204392 -15.01013)
		(width 0.1397)
		(layer "F.Cu")
		(net "P2E_CPU_SAS_RX_DP4")
	)
	(segment
		(start 38.6715 -9.641078)
		(end 38.6715 -6.07568)
		(width 0.1397)
		(layer "F.Cu")
		(net "P2E_CPU_SAS_RX_DP4")
	)
	(segment
		(start 38.80104 -13.578078)
		(end 39.1414 -13.237718)
		(width 0.1397)
		(layer "F.Cu")
		(net "P2E_CPU_SAS_RX_DP4")
	)
	(segment
		(start 39.15156 -11.447018)
		(end 39.15156 -10.857738)
		(width 0.1397)
		(layer "F.Cu")
		(net "P2E_CPU_SAS_RX_DP4")
	)
	(segment
		(start 38.3413 -10.530078)
		(end 38.2016 -10.390378)
		(width 0.1397)
		(layer "F.Cu")
		(net "P2E_CPU_SAS_RX_DP4")
	)
	(segment
		(start 38.999668 -18.650204)
		(end 39.000938 -18.648934)
		(width 0.1397)
		(layer "F.Cu")
		(net "P2E_CPU_SAS_RX_DP4")
	)
	(segment
		(start 38.8239 -10.530078)
		(end 38.3413 -10.530078)
		(width 0.1397)
		(layer "F.Cu")
		(net "P2E_CPU_SAS_RX_DP4")
	)
	(segment
		(start 38.3413 -12.333478)
		(end 38.2016 -12.193778)
		(width 0.1397)
		(layer "F.Cu")
		(net "P2E_CPU_SAS_RX_DP4")
	)
	(segment
		(start 38.2016 -10.110978)
		(end 38.6715 -9.641078)
		(width 0.1397)
		(layer "F.Cu")
		(net "P2E_CPU_SAS_RX_DP4")
	)
	(segment
		(start 38.999922 -18.650204)
		(end 38.999668 -18.650204)
		(width 0.1397)
		(layer "F.Cu")
		(net "P2E_CPU_SAS_RX_DP4")
	)
	(segment
		(start 38.2016 -10.390378)
		(end 38.2016 -10.110978)
		(width 0.1397)
		(layer "F.Cu")
		(net "P2E_CPU_SAS_RX_DP4")
	)
	(segment
		(start 38.3413 -11.774678)
		(end 38.8239 -11.774678)
		(width 0.1397)
		(layer "F.Cu")
		(net "P2E_CPU_SAS_RX_DP4")
	)
	(segment
		(start 38.2016 -13.717778)
		(end 38.3413 -13.578078)
		(width 0.1397)
		(layer "F.Cu")
		(net "P2E_CPU_SAS_RX_DP4")
	)
	(segment
		(start 38.8239 -11.774678)
		(end 39.15156 -11.447018)
		(width 0.1397)
		(layer "F.Cu")
		(net "P2E_CPU_SAS_RX_DP4")
	)
	(segment
		(start 38.3413 -13.578078)
		(end 38.80104 -13.578078)
		(width 0.1397)
		(layer "F.Cu")
		(net "P2E_CPU_SAS_RX_DP4")
	)
	(segment
		(start 39.000938 -18.648934)
		(end 39.000938 -17.551654)
		(width 0.1397)
		(layer "F.Cu")
		(net "P2E_CPU_SAS_RX_DP4")
	)
	(segment
		(start 39.1414 -12.673838)
		(end 38.80104 -12.333478)
		(width 0.1397)
		(layer "F.Cu")
		(net "P2E_CPU_SAS_RX_DP4")
	)
	(segment
		(start 38.999922 -5.747258)
		(end 38.999922 -3.495548)
		(width 0.1397)
		(layer "F.Cu")
		(net "P2E_CPU_SAS_RX_DP4")
	)
	(segment
		(start 38.6715 -6.07568)
		(end 38.999922 -5.747258)
		(width 0.1397)
		(layer "F.Cu")
		(net "P2E_CPU_SAS_RX_DP4")
	)
	(segment
		(start 38.2016 -14.007338)
		(end 38.2016 -13.717778)
		(width 0.1397)
		(layer "F.Cu")
		(net "P2E_CPU_SAS_RX_DP4")
	)
	(segment
		(start 38.80104 -12.333478)
		(end 38.3413 -12.333478)
		(width 0.1397)
		(layer "F.Cu")
		(net "P2E_CPU_SAS_RX_DP4")
	)
	(segment
		(start 39.1414 -13.237718)
		(end 39.1414 -12.673838)
		(width 0.1397)
		(layer "F.Cu")
		(net "P2E_CPU_SAS_RX_DP4")
	)
	(segment
		(start 39.000938 -17.551654)
		(end 39.204392 -17.3482)
		(width 0.1397)
		(layer "F.Cu")
		(net "P2E_CPU_SAS_RX_DP4")
	)
	(segment
		(start 34.328608 -9.496298)
		(end 34.328608 -6.07568)
		(width 0.1397)
		(layer "F.Cu")
		(net "P2E_CPU_SAS_RX_DN5")
	)
	(segment
		(start 34.661856 -13.235686)
		(end 34.801556 -13.095986)
		(width 0.1397)
		(layer "F.Cu")
		(net "P2E_CPU_SAS_RX_DN5")
	)
	(segment
		(start 33.999932 -5.747004)
		(end 33.999932 -3.495548)
		(width 0.1397)
		(layer "F.Cu")
		(net "P2E_CPU_SAS_RX_DN5")
	)
	(segment
		(start 34.667952 -17.399)
		(end 34.860992 -17.20596)
		(width 0.1397)
		(layer "F.Cu")
		(net "P2E_CPU_SAS_RX_DN5")
	)
	(segment
		(start 34.860992 -15.15237)
		(end 33.85566 -14.147038)
		(width 0.1397)
		(layer "F.Cu")
		(net "P2E_CPU_SAS_RX_DN5")
	)
	(segment
		(start 34.801556 -11.013186)
		(end 34.661856 -10.873486)
		(width 0.1397)
		(layer "F.Cu")
		(net "P2E_CPU_SAS_RX_DN5")
	)
	(segment
		(start 33.999932 -16.649954)
		(end 33.999678 -16.649954)
		(width 0.1397)
		(layer "F.Cu")
		(net "P2E_CPU_SAS_RX_DN5")
	)
	(segment
		(start 33.85566 -9.969246)
		(end 34.328608 -9.496298)
		(width 0.1397)
		(layer "F.Cu")
		(net "P2E_CPU_SAS_RX_DN5")
	)
	(segment
		(start 33.85566 -11.772646)
		(end 34.19602 -11.432286)
		(width 0.1397)
		(layer "F.Cu")
		(net "P2E_CPU_SAS_RX_DN5")
	)
	(segment
		(start 33.85566 -12.336526)
		(end 33.85566 -11.772646)
		(width 0.1397)
		(layer "F.Cu")
		(net "P2E_CPU_SAS_RX_DN5")
	)
	(segment
		(start 34.328608 -6.07568)
		(end 33.999932 -5.747004)
		(width 0.1397)
		(layer "F.Cu")
		(net "P2E_CPU_SAS_RX_DN5")
	)
	(segment
		(start 33.85566 -13.576046)
		(end 34.19602 -13.235686)
		(width 0.1397)
		(layer "F.Cu")
		(net "P2E_CPU_SAS_RX_DN5")
	)
	(segment
		(start 33.999678 -16.649954)
		(end 33.999678 -17.134586)
		(width 0.1397)
		(layer "F.Cu")
		(net "P2E_CPU_SAS_RX_DN5")
	)
	(segment
		(start 33.999678 -17.134586)
		(end 34.264092 -17.399)
		(width 0.1397)
		(layer "F.Cu")
		(net "P2E_CPU_SAS_RX_DN5")
	)
	(segment
		(start 34.661856 -12.676886)
		(end 34.19602 -12.676886)
		(width 0.1397)
		(layer "F.Cu")
		(net "P2E_CPU_SAS_RX_DN5")
	)
	(segment
		(start 34.860992 -17.20596)
		(end 34.860992 -15.15237)
		(width 0.1397)
		(layer "F.Cu")
		(net "P2E_CPU_SAS_RX_DN5")
	)
	(segment
		(start 34.801556 -13.095986)
		(end 34.801556 -12.816586)
		(width 0.1397)
		(layer "F.Cu")
		(net "P2E_CPU_SAS_RX_DN5")
	)
	(segment
		(start 34.801556 -11.292586)
		(end 34.801556 -11.013186)
		(width 0.1397)
		(layer "F.Cu")
		(net "P2E_CPU_SAS_RX_DN5")
	)
	(segment
		(start 34.264092 -17.399)
		(end 34.667952 -17.399)
		(width 0.1397)
		(layer "F.Cu")
		(net "P2E_CPU_SAS_RX_DN5")
	)
	(segment
		(start 33.85566 -14.147038)
		(end 33.85566 -13.576046)
		(width 0.1397)
		(layer "F.Cu")
		(net "P2E_CPU_SAS_RX_DN5")
	)
	(segment
		(start 34.19602 -13.235686)
		(end 34.661856 -13.235686)
		(width 0.1397)
		(layer "F.Cu")
		(net "P2E_CPU_SAS_RX_DN5")
	)
	(segment
		(start 34.19602 -11.432286)
		(end 34.661856 -11.432286)
		(width 0.1397)
		(layer "F.Cu")
		(net "P2E_CPU_SAS_RX_DN5")
	)
	(segment
		(start 34.19602 -10.873486)
		(end 33.85566 -10.533126)
		(width 0.1397)
		(layer "F.Cu")
		(net "P2E_CPU_SAS_RX_DN5")
	)
	(segment
		(start 34.661856 -10.873486)
		(end 34.19602 -10.873486)
		(width 0.1397)
		(layer "F.Cu")
		(net "P2E_CPU_SAS_RX_DN5")
	)
	(segment
		(start 34.661856 -11.432286)
		(end 34.801556 -11.292586)
		(width 0.1397)
		(layer "F.Cu")
		(net "P2E_CPU_SAS_RX_DN5")
	)
	(segment
		(start 34.19602 -12.676886)
		(end 33.85566 -12.336526)
		(width 0.1397)
		(layer "F.Cu")
		(net "P2E_CPU_SAS_RX_DN5")
	)
	(segment
		(start 34.801556 -12.816586)
		(end 34.661856 -12.676886)
		(width 0.1397)
		(layer "F.Cu")
		(net "P2E_CPU_SAS_RX_DN5")
	)
	(segment
		(start 33.85566 -10.533126)
		(end 33.85566 -9.969246)
		(width 0.1397)
		(layer "F.Cu")
		(net "P2E_CPU_SAS_RX_DN5")
	)
	(segment
		(start 34.671508 -9.638538)
		(end 34.671508 -6.07568)
		(width 0.1397)
		(layer "F.Cu")
		(net "P2E_CPU_SAS_RX_DP5")
	)
	(segment
		(start 34.99993 -5.747258)
		(end 34.99993 -3.495548)
		(width 0.1397)
		(layer "F.Cu")
		(net "P2E_CPU_SAS_RX_DP5")
	)
	(segment
		(start 34.19856 -12.194286)
		(end 34.19856 -11.914886)
		(width 0.1397)
		(layer "F.Cu")
		(net "P2E_CPU_SAS_RX_DP5")
	)
	(segment
		(start 35.000438 -18.650204)
		(end 35.000438 -17.551654)
		(width 0.1397)
		(layer "F.Cu")
		(net "P2E_CPU_SAS_RX_DP5")
	)
	(segment
		(start 34.33826 -12.333986)
		(end 34.19856 -12.194286)
		(width 0.1397)
		(layer "F.Cu")
		(net "P2E_CPU_SAS_RX_DP5")
	)
	(segment
		(start 34.804096 -13.578586)
		(end 35.144456 -13.238226)
		(width 0.1397)
		(layer "F.Cu")
		(net "P2E_CPU_SAS_RX_DP5")
	)
	(segment
		(start 34.19856 -10.111486)
		(end 34.671508 -9.638538)
		(width 0.1397)
		(layer "F.Cu")
		(net "P2E_CPU_SAS_RX_DP5")
	)
	(segment
		(start 34.804096 -11.775186)
		(end 35.144456 -11.434826)
		(width 0.1397)
		(layer "F.Cu")
		(net "P2E_CPU_SAS_RX_DP5")
	)
	(segment
		(start 35.000692 -18.650204)
		(end 35.000438 -18.650204)
		(width 0.1397)
		(layer "F.Cu")
		(net "P2E_CPU_SAS_RX_DP5")
	)
	(segment
		(start 34.33826 -13.578586)
		(end 34.804096 -13.578586)
		(width 0.1397)
		(layer "F.Cu")
		(net "P2E_CPU_SAS_RX_DP5")
	)
	(segment
		(start 35.144456 -13.238226)
		(end 35.144456 -12.674346)
		(width 0.1397)
		(layer "F.Cu")
		(net "P2E_CPU_SAS_RX_DP5")
	)
	(segment
		(start 34.33826 -11.775186)
		(end 34.804096 -11.775186)
		(width 0.1397)
		(layer "F.Cu")
		(net "P2E_CPU_SAS_RX_DP5")
	)
	(segment
		(start 34.671508 -6.07568)
		(end 34.99993 -5.747258)
		(width 0.1397)
		(layer "F.Cu")
		(net "P2E_CPU_SAS_RX_DP5")
	)
	(segment
		(start 34.19856 -14.004798)
		(end 34.19856 -13.718286)
		(width 0.1397)
		(layer "F.Cu")
		(net "P2E_CPU_SAS_RX_DP5")
	)
	(segment
		(start 35.144456 -12.674346)
		(end 34.804096 -12.333986)
		(width 0.1397)
		(layer "F.Cu")
		(net "P2E_CPU_SAS_RX_DP5")
	)
	(segment
		(start 34.804096 -12.333986)
		(end 34.33826 -12.333986)
		(width 0.1397)
		(layer "F.Cu")
		(net "P2E_CPU_SAS_RX_DP5")
	)
	(segment
		(start 34.19856 -11.914886)
		(end 34.33826 -11.775186)
		(width 0.1397)
		(layer "F.Cu")
		(net "P2E_CPU_SAS_RX_DP5")
	)
	(segment
		(start 35.203892 -15.01013)
		(end 34.19856 -14.004798)
		(width 0.1397)
		(layer "F.Cu")
		(net "P2E_CPU_SAS_RX_DP5")
	)
	(segment
		(start 34.19856 -13.718286)
		(end 34.33826 -13.578586)
		(width 0.1397)
		(layer "F.Cu")
		(net "P2E_CPU_SAS_RX_DP5")
	)
	(segment
		(start 34.804096 -10.530586)
		(end 34.33826 -10.530586)
		(width 0.1397)
		(layer "F.Cu")
		(net "P2E_CPU_SAS_RX_DP5")
	)
	(segment
		(start 35.144456 -11.434826)
		(end 35.144456 -10.870946)
		(width 0.1397)
		(layer "F.Cu")
		(net "P2E_CPU_SAS_RX_DP5")
	)
	(segment
		(start 35.144456 -10.870946)
		(end 34.804096 -10.530586)
		(width 0.1397)
		(layer "F.Cu")
		(net "P2E_CPU_SAS_RX_DP5")
	)
	(segment
		(start 34.33826 -10.530586)
		(end 34.19856 -10.390886)
		(width 0.1397)
		(layer "F.Cu")
		(net "P2E_CPU_SAS_RX_DP5")
	)
	(segment
		(start 35.000438 -17.551654)
		(end 35.203892 -17.3482)
		(width 0.1397)
		(layer "F.Cu")
		(net "P2E_CPU_SAS_RX_DP5")
	)
	(segment
		(start 34.19856 -10.390886)
		(end 34.19856 -10.111486)
		(width 0.1397)
		(layer "F.Cu")
		(net "P2E_CPU_SAS_RX_DP5")
	)
	(segment
		(start 35.203892 -17.3482)
		(end 35.203892 -15.01013)
		(width 0.1397)
		(layer "F.Cu")
		(net "P2E_CPU_SAS_RX_DP5")
	)
	(segment
		(start 30.664912 -11.431524)
		(end 30.804612 -11.291824)
		(width 0.1397)
		(layer "F.Cu")
		(net "P2E_CPU_SAS_RX_DN6")
	)
	(segment
		(start 30.19298 -13.234924)
		(end 30.664912 -13.234924)
		(width 0.1397)
		(layer "F.Cu")
		(net "P2E_CPU_SAS_RX_DN6")
	)
	(segment
		(start 29.85262 -13.575284)
		(end 30.19298 -13.234924)
		(width 0.1397)
		(layer "F.Cu")
		(net "P2E_CPU_SAS_RX_DN6")
	)
	(segment
		(start 29.85262 -12.335764)
		(end 29.85262 -11.771884)
		(width 0.1397)
		(layer "F.Cu")
		(net "P2E_CPU_SAS_RX_DN6")
	)
	(segment
		(start 30.664912 -10.872724)
		(end 30.19298 -10.872724)
		(width 0.1397)
		(layer "F.Cu")
		(net "P2E_CPU_SAS_RX_DN6")
	)
	(segment
		(start 29.85262 -9.968484)
		(end 30.328616 -9.492488)
		(width 0.1397)
		(layer "F.Cu")
		(net "P2E_CPU_SAS_RX_DN6")
	)
	(segment
		(start 30.804612 -11.012424)
		(end 30.664912 -10.872724)
		(width 0.1397)
		(layer "F.Cu")
		(net "P2E_CPU_SAS_RX_DN6")
	)
	(segment
		(start 30.000448 -16.649954)
		(end 30.000448 -17.134586)
		(width 0.1397)
		(layer "F.Cu")
		(net "P2E_CPU_SAS_RX_DN6")
	)
	(segment
		(start 30.19298 -11.431524)
		(end 30.664912 -11.431524)
		(width 0.1397)
		(layer "F.Cu")
		(net "P2E_CPU_SAS_RX_DN6")
	)
	(segment
		(start 30.861762 -15.15237)
		(end 29.85262 -14.143228)
		(width 0.1397)
		(layer "F.Cu")
		(net "P2E_CPU_SAS_RX_DN6")
	)
	(segment
		(start 30.664912 -13.234924)
		(end 30.804612 -13.095224)
		(width 0.1397)
		(layer "F.Cu")
		(net "P2E_CPU_SAS_RX_DN6")
	)
	(segment
		(start 30.664912 -12.676124)
		(end 30.19298 -12.676124)
		(width 0.1397)
		(layer "F.Cu")
		(net "P2E_CPU_SAS_RX_DN6")
	)
	(segment
		(start 30.328616 -9.492488)
		(end 30.328616 -6.07568)
		(width 0.1397)
		(layer "F.Cu")
		(net "P2E_CPU_SAS_RX_DN6")
	)
	(segment
		(start 30.19298 -12.676124)
		(end 29.85262 -12.335764)
		(width 0.1397)
		(layer "F.Cu")
		(net "P2E_CPU_SAS_RX_DN6")
	)
	(segment
		(start 30.000702 -16.649954)
		(end 30.000448 -16.649954)
		(width 0.1397)
		(layer "F.Cu")
		(net "P2E_CPU_SAS_RX_DN6")
	)
	(segment
		(start 30.668722 -17.399)
		(end 30.861762 -17.20596)
		(width 0.1397)
		(layer "F.Cu")
		(net "P2E_CPU_SAS_RX_DN6")
	)
	(segment
		(start 30.861762 -17.20596)
		(end 30.861762 -15.15237)
		(width 0.1397)
		(layer "F.Cu")
		(net "P2E_CPU_SAS_RX_DN6")
	)
	(segment
		(start 29.85262 -11.771884)
		(end 30.19298 -11.431524)
		(width 0.1397)
		(layer "F.Cu")
		(net "P2E_CPU_SAS_RX_DN6")
	)
	(segment
		(start 30.19298 -10.872724)
		(end 29.85262 -10.532364)
		(width 0.1397)
		(layer "F.Cu")
		(net "P2E_CPU_SAS_RX_DN6")
	)
	(segment
		(start 30.328616 -6.07568)
		(end 29.99994 -5.747004)
		(width 0.1397)
		(layer "F.Cu")
		(net "P2E_CPU_SAS_RX_DN6")
	)
	(segment
		(start 29.85262 -14.143228)
		(end 29.85262 -13.575284)
		(width 0.1397)
		(layer "F.Cu")
		(net "P2E_CPU_SAS_RX_DN6")
	)
	(segment
		(start 30.804612 -11.291824)
		(end 30.804612 -11.012424)
		(width 0.1397)
		(layer "F.Cu")
		(net "P2E_CPU_SAS_RX_DN6")
	)
	(segment
		(start 30.804612 -13.095224)
		(end 30.804612 -12.815824)
		(width 0.1397)
		(layer "F.Cu")
		(net "P2E_CPU_SAS_RX_DN6")
	)
	(segment
		(start 30.264862 -17.399)
		(end 30.668722 -17.399)
		(width 0.1397)
		(layer "F.Cu")
		(net "P2E_CPU_SAS_RX_DN6")
	)
	(segment
		(start 29.99994 -5.747004)
		(end 29.99994 -3.495548)
		(width 0.1397)
		(layer "F.Cu")
		(net "P2E_CPU_SAS_RX_DN6")
	)
	(segment
		(start 30.000448 -17.134586)
		(end 30.264862 -17.399)
		(width 0.1397)
		(layer "F.Cu")
		(net "P2E_CPU_SAS_RX_DN6")
	)
	(segment
		(start 29.85262 -10.532364)
		(end 29.85262 -9.968484)
		(width 0.1397)
		(layer "F.Cu")
		(net "P2E_CPU_SAS_RX_DN6")
	)
	(segment
		(start 30.804612 -12.815824)
		(end 30.664912 -12.676124)
		(width 0.1397)
		(layer "F.Cu")
		(net "P2E_CPU_SAS_RX_DN6")
	)
	(segment
		(start 31.204662 -15.01013)
		(end 30.19552 -14.000988)
		(width 0.1397)
		(layer "F.Cu")
		(net "P2E_CPU_SAS_RX_DP6")
	)
	(segment
		(start 30.807152 -10.529824)
		(end 30.33522 -10.529824)
		(width 0.1397)
		(layer "F.Cu")
		(net "P2E_CPU_SAS_RX_DP6")
	)
	(segment
		(start 30.19552 -11.914124)
		(end 30.33522 -11.774424)
		(width 0.1397)
		(layer "F.Cu")
		(net "P2E_CPU_SAS_RX_DP6")
	)
	(segment
		(start 30.807152 -13.577824)
		(end 31.147512 -13.237464)
		(width 0.1397)
		(layer "F.Cu")
		(net "P2E_CPU_SAS_RX_DP6")
	)
	(segment
		(start 30.671516 -6.07568)
		(end 30.999938 -5.747258)
		(width 0.1397)
		(layer "F.Cu")
		(net "P2E_CPU_SAS_RX_DP6")
	)
	(segment
		(start 30.19552 -14.000988)
		(end 30.19552 -13.717524)
		(width 0.1397)
		(layer "F.Cu")
		(net "P2E_CPU_SAS_RX_DP6")
	)
	(segment
		(start 31.147512 -10.870184)
		(end 30.807152 -10.529824)
		(width 0.1397)
		(layer "F.Cu")
		(net "P2E_CPU_SAS_RX_DP6")
	)
	(segment
		(start 30.33522 -12.333224)
		(end 30.19552 -12.193524)
		(width 0.1397)
		(layer "F.Cu")
		(net "P2E_CPU_SAS_RX_DP6")
	)
	(segment
		(start 31.000192 -18.650204)
		(end 30.999938 -18.650204)
		(width 0.1397)
		(layer "F.Cu")
		(net "P2E_CPU_SAS_RX_DP6")
	)
	(segment
		(start 30.671516 -9.634728)
		(end 30.671516 -6.07568)
		(width 0.1397)
		(layer "F.Cu")
		(net "P2E_CPU_SAS_RX_DP6")
	)
	(segment
		(start 31.001208 -18.648934)
		(end 31.001208 -17.551654)
		(width 0.1397)
		(layer "F.Cu")
		(net "P2E_CPU_SAS_RX_DP6")
	)
	(segment
		(start 30.19552 -10.390124)
		(end 30.19552 -10.110724)
		(width 0.1397)
		(layer "F.Cu")
		(net "P2E_CPU_SAS_RX_DP6")
	)
	(segment
		(start 30.19552 -10.110724)
		(end 30.671516 -9.634728)
		(width 0.1397)
		(layer "F.Cu")
		(net "P2E_CPU_SAS_RX_DP6")
	)
	(segment
		(start 30.999938 -5.747258)
		(end 30.999938 -3.495548)
		(width 0.1397)
		(layer "F.Cu")
		(net "P2E_CPU_SAS_RX_DP6")
	)
	(segment
		(start 30.33522 -13.577824)
		(end 30.807152 -13.577824)
		(width 0.1397)
		(layer "F.Cu")
		(net "P2E_CPU_SAS_RX_DP6")
	)
	(segment
		(start 30.19552 -13.717524)
		(end 30.33522 -13.577824)
		(width 0.1397)
		(layer "F.Cu")
		(net "P2E_CPU_SAS_RX_DP6")
	)
	(segment
		(start 30.19552 -12.193524)
		(end 30.19552 -11.914124)
		(width 0.1397)
		(layer "F.Cu")
		(net "P2E_CPU_SAS_RX_DP6")
	)
	(segment
		(start 30.807152 -12.333224)
		(end 30.33522 -12.333224)
		(width 0.1397)
		(layer "F.Cu")
		(net "P2E_CPU_SAS_RX_DP6")
	)
	(segment
		(start 30.33522 -10.529824)
		(end 30.19552 -10.390124)
		(width 0.1397)
		(layer "F.Cu")
		(net "P2E_CPU_SAS_RX_DP6")
	)
	(segment
		(start 30.999938 -18.650204)
		(end 31.001208 -18.648934)
		(width 0.1397)
		(layer "F.Cu")
		(net "P2E_CPU_SAS_RX_DP6")
	)
	(segment
		(start 30.33522 -11.774424)
		(end 30.807152 -11.774424)
		(width 0.1397)
		(layer "F.Cu")
		(net "P2E_CPU_SAS_RX_DP6")
	)
	(segment
		(start 31.204662 -17.3482)
		(end 31.204662 -15.01013)
		(width 0.1397)
		(layer "F.Cu")
		(net "P2E_CPU_SAS_RX_DP6")
	)
	(segment
		(start 31.147512 -13.237464)
		(end 31.147512 -12.673584)
		(width 0.1397)
		(layer "F.Cu")
		(net "P2E_CPU_SAS_RX_DP6")
	)
	(segment
		(start 31.147512 -11.434064)
		(end 31.147512 -10.870184)
		(width 0.1397)
		(layer "F.Cu")
		(net "P2E_CPU_SAS_RX_DP6")
	)
	(segment
		(start 31.147512 -12.673584)
		(end 30.807152 -12.333224)
		(width 0.1397)
		(layer "F.Cu")
		(net "P2E_CPU_SAS_RX_DP6")
	)
	(segment
		(start 30.807152 -11.774424)
		(end 31.147512 -11.434064)
		(width 0.1397)
		(layer "F.Cu")
		(net "P2E_CPU_SAS_RX_DP6")
	)
	(segment
		(start 31.001208 -17.551654)
		(end 31.204662 -17.3482)
		(width 0.1397)
		(layer "F.Cu")
		(net "P2E_CPU_SAS_RX_DP6")
	)
	(segment
		(start 26.18994 -13.235432)
		(end 26.667968 -13.235432)
		(width 0.1397)
		(layer "F.Cu")
		(net "P2E_CPU_SAS_RX_DN7")
	)
	(segment
		(start 26.667968 -13.235432)
		(end 26.807668 -13.095732)
		(width 0.1397)
		(layer "F.Cu")
		(net "P2E_CPU_SAS_RX_DN7")
	)
	(segment
		(start 26.328624 -9.489948)
		(end 26.328624 -6.07568)
		(width 0.1397)
		(layer "F.Cu")
		(net "P2E_CPU_SAS_RX_DN7")
	)
	(segment
		(start 26.000202 -16.649954)
		(end 25.999948 -16.649954)
		(width 0.1397)
		(layer "F.Cu")
		(net "P2E_CPU_SAS_RX_DN7")
	)
	(segment
		(start 26.861262 -15.15237)
		(end 25.84958 -14.140688)
		(width 0.1397)
		(layer "F.Cu")
		(net "P2E_CPU_SAS_RX_DN7")
	)
	(segment
		(start 26.807668 -11.292332)
		(end 26.807668 -11.012932)
		(width 0.1397)
		(layer "F.Cu")
		(net "P2E_CPU_SAS_RX_DN7")
	)
	(segment
		(start 26.18994 -10.873232)
		(end 25.84958 -10.532872)
		(width 0.1397)
		(layer "F.Cu")
		(net "P2E_CPU_SAS_RX_DN7")
	)
	(segment
		(start 26.807668 -11.012932)
		(end 26.667968 -10.873232)
		(width 0.1397)
		(layer "F.Cu")
		(net "P2E_CPU_SAS_RX_DN7")
	)
	(segment
		(start 26.668222 -17.399)
		(end 26.861262 -17.20596)
		(width 0.1397)
		(layer "F.Cu")
		(net "P2E_CPU_SAS_RX_DN7")
	)
	(segment
		(start 25.84958 -11.772392)
		(end 26.18994 -11.432032)
		(width 0.1397)
		(layer "F.Cu")
		(net "P2E_CPU_SAS_RX_DN7")
	)
	(segment
		(start 26.807668 -13.095732)
		(end 26.807668 -12.816332)
		(width 0.1397)
		(layer "F.Cu")
		(net "P2E_CPU_SAS_RX_DN7")
	)
	(segment
		(start 26.667968 -11.432032)
		(end 26.807668 -11.292332)
		(width 0.1397)
		(layer "F.Cu")
		(net "P2E_CPU_SAS_RX_DN7")
	)
	(segment
		(start 26.18994 -11.432032)
		(end 26.667968 -11.432032)
		(width 0.1397)
		(layer "F.Cu")
		(net "P2E_CPU_SAS_RX_DN7")
	)
	(segment
		(start 25.84958 -10.532872)
		(end 25.84958 -9.968992)
		(width 0.1397)
		(layer "F.Cu")
		(net "P2E_CPU_SAS_RX_DN7")
	)
	(segment
		(start 26.861262 -17.20596)
		(end 26.861262 -15.15237)
		(width 0.1397)
		(layer "F.Cu")
		(net "P2E_CPU_SAS_RX_DN7")
	)
	(segment
		(start 25.999948 -16.649954)
		(end 25.999948 -17.134586)
		(width 0.1397)
		(layer "F.Cu")
		(net "P2E_CPU_SAS_RX_DN7")
	)
	(segment
		(start 25.84958 -9.968992)
		(end 26.328624 -9.489948)
		(width 0.1397)
		(layer "F.Cu")
		(net "P2E_CPU_SAS_RX_DN7")
	)
	(segment
		(start 26.667968 -10.873232)
		(end 26.18994 -10.873232)
		(width 0.1397)
		(layer "F.Cu")
		(net "P2E_CPU_SAS_RX_DN7")
	)
	(segment
		(start 26.264362 -17.399)
		(end 26.668222 -17.399)
		(width 0.1397)
		(layer "F.Cu")
		(net "P2E_CPU_SAS_RX_DN7")
	)
	(segment
		(start 26.667968 -12.676632)
		(end 26.18994 -12.676632)
		(width 0.1397)
		(layer "F.Cu")
		(net "P2E_CPU_SAS_RX_DN7")
	)
	(segment
		(start 26.328624 -6.07568)
		(end 25.999948 -5.747004)
		(width 0.1397)
		(layer "F.Cu")
		(net "P2E_CPU_SAS_RX_DN7")
	)
	(segment
		(start 25.84958 -12.336272)
		(end 25.84958 -11.772392)
		(width 0.1397)
		(layer "F.Cu")
		(net "P2E_CPU_SAS_RX_DN7")
	)
	(segment
		(start 26.18994 -12.676632)
		(end 25.84958 -12.336272)
		(width 0.1397)
		(layer "F.Cu")
		(net "P2E_CPU_SAS_RX_DN7")
	)
	(segment
		(start 25.999948 -17.134586)
		(end 26.264362 -17.399)
		(width 0.1397)
		(layer "F.Cu")
		(net "P2E_CPU_SAS_RX_DN7")
	)
	(segment
		(start 25.84958 -14.140688)
		(end 25.84958 -13.575792)
		(width 0.1397)
		(layer "F.Cu")
		(net "P2E_CPU_SAS_RX_DN7")
	)
	(segment
		(start 25.84958 -13.575792)
		(end 26.18994 -13.235432)
		(width 0.1397)
		(layer "F.Cu")
		(net "P2E_CPU_SAS_RX_DN7")
	)
	(segment
		(start 26.807668 -12.816332)
		(end 26.667968 -12.676632)
		(width 0.1397)
		(layer "F.Cu")
		(net "P2E_CPU_SAS_RX_DN7")
	)
	(segment
		(start 25.999948 -5.747004)
		(end 25.999948 -3.495548)
		(width 0.1397)
		(layer "F.Cu")
		(net "P2E_CPU_SAS_RX_DN7")
	)
	(segment
		(start 27.150568 -11.434572)
		(end 27.150568 -10.870692)
		(width 0.1397)
		(layer "F.Cu")
		(net "P2E_CPU_SAS_RX_DP7")
	)
	(segment
		(start 26.19248 -12.194032)
		(end 26.19248 -11.914632)
		(width 0.1397)
		(layer "F.Cu")
		(net "P2E_CPU_SAS_RX_DP7")
	)
	(segment
		(start 26.33218 -10.530332)
		(end 26.19248 -10.390632)
		(width 0.1397)
		(layer "F.Cu")
		(net "P2E_CPU_SAS_RX_DP7")
	)
	(segment
		(start 27.150568 -12.674092)
		(end 26.810208 -12.333732)
		(width 0.1397)
		(layer "F.Cu")
		(net "P2E_CPU_SAS_RX_DP7")
	)
	(segment
		(start 26.19248 -10.111232)
		(end 26.671524 -9.632188)
		(width 0.1397)
		(layer "F.Cu")
		(net "P2E_CPU_SAS_RX_DP7")
	)
	(segment
		(start 27.000708 -17.551654)
		(end 27.204162 -17.3482)
		(width 0.1397)
		(layer "F.Cu")
		(net "P2E_CPU_SAS_RX_DP7")
	)
	(segment
		(start 26.810208 -11.774932)
		(end 27.150568 -11.434572)
		(width 0.1397)
		(layer "F.Cu")
		(net "P2E_CPU_SAS_RX_DP7")
	)
	(segment
		(start 27.150568 -13.237972)
		(end 27.150568 -12.674092)
		(width 0.1397)
		(layer "F.Cu")
		(net "P2E_CPU_SAS_RX_DP7")
	)
	(segment
		(start 26.810208 -12.333732)
		(end 26.33218 -12.333732)
		(width 0.1397)
		(layer "F.Cu")
		(net "P2E_CPU_SAS_RX_DP7")
	)
	(segment
		(start 26.999438 -18.650204)
		(end 27.000708 -18.648934)
		(width 0.1397)
		(layer "F.Cu")
		(net "P2E_CPU_SAS_RX_DP7")
	)
	(segment
		(start 26.33218 -12.333732)
		(end 26.19248 -12.194032)
		(width 0.1397)
		(layer "F.Cu")
		(net "P2E_CPU_SAS_RX_DP7")
	)
	(segment
		(start 26.33218 -11.774932)
		(end 26.810208 -11.774932)
		(width 0.1397)
		(layer "F.Cu")
		(net "P2E_CPU_SAS_RX_DP7")
	)
	(segment
		(start 26.999692 -18.650204)
		(end 26.999438 -18.650204)
		(width 0.1397)
		(layer "F.Cu")
		(net "P2E_CPU_SAS_RX_DP7")
	)
	(segment
		(start 26.671524 -6.07568)
		(end 26.999946 -5.747258)
		(width 0.1397)
		(layer "F.Cu")
		(net "P2E_CPU_SAS_RX_DP7")
	)
	(segment
		(start 27.204162 -17.3482)
		(end 27.204162 -15.01013)
		(width 0.1397)
		(layer "F.Cu")
		(net "P2E_CPU_SAS_RX_DP7")
	)
	(segment
		(start 27.150568 -10.870692)
		(end 26.810208 -10.530332)
		(width 0.1397)
		(layer "F.Cu")
		(net "P2E_CPU_SAS_RX_DP7")
	)
	(segment
		(start 26.671524 -9.632188)
		(end 26.671524 -6.07568)
		(width 0.1397)
		(layer "F.Cu")
		(net "P2E_CPU_SAS_RX_DP7")
	)
	(segment
		(start 26.810208 -10.530332)
		(end 26.33218 -10.530332)
		(width 0.1397)
		(layer "F.Cu")
		(net "P2E_CPU_SAS_RX_DP7")
	)
	(segment
		(start 26.33218 -13.578332)
		(end 26.810208 -13.578332)
		(width 0.1397)
		(layer "F.Cu")
		(net "P2E_CPU_SAS_RX_DP7")
	)
	(segment
		(start 26.999946 -5.747258)
		(end 26.999946 -3.495548)
		(width 0.1397)
		(layer "F.Cu")
		(net "P2E_CPU_SAS_RX_DP7")
	)
	(segment
		(start 26.19248 -10.390632)
		(end 26.19248 -10.111232)
		(width 0.1397)
		(layer "F.Cu")
		(net "P2E_CPU_SAS_RX_DP7")
	)
	(segment
		(start 26.19248 -13.718032)
		(end 26.33218 -13.578332)
		(width 0.1397)
		(layer "F.Cu")
		(net "P2E_CPU_SAS_RX_DP7")
	)
	(segment
		(start 27.204162 -15.01013)
		(end 26.19248 -13.998448)
		(width 0.1397)
		(layer "F.Cu")
		(net "P2E_CPU_SAS_RX_DP7")
	)
	(segment
		(start 26.810208 -13.578332)
		(end 27.150568 -13.237972)
		(width 0.1397)
		(layer "F.Cu")
		(net "P2E_CPU_SAS_RX_DP7")
	)
	(segment
		(start 26.19248 -13.998448)
		(end 26.19248 -13.718032)
		(width 0.1397)
		(layer "F.Cu")
		(net "P2E_CPU_SAS_RX_DP7")
	)
	(segment
		(start 26.19248 -11.914632)
		(end 26.33218 -11.774932)
		(width 0.1397)
		(layer "F.Cu")
		(net "P2E_CPU_SAS_RX_DP7")
	)
	(segment
		(start 27.000708 -18.648934)
		(end 27.000708 -17.551654)
		(width 0.1397)
		(layer "F.Cu")
		(net "P2E_CPU_SAS_RX_DP7")
	)
	(segment
		(start 21.999448 -17.134586)
		(end 22.299422 -17.43456)
		(width 0.1397)
		(layer "F.Cu")
		(net "P2E_CPU_ETH10G_RX_DN8")
	)
	(segment
		(start 22.299422 -17.43456)
		(end 22.632162 -17.43456)
		(width 0.1397)
		(layer "F.Cu")
		(net "P2E_CPU_ETH10G_RX_DN8")
	)
	(segment
		(start 22.860762 -15.15237)
		(end 22.328378 -14.619986)
		(width 0.1397)
		(layer "F.Cu")
		(net "P2E_CPU_ETH10G_RX_DN8")
	)
	(segment
		(start 22.860762 -17.20596)
		(end 22.860762 -15.15237)
		(width 0.1397)
		(layer "F.Cu")
		(net "P2E_CPU_ETH10G_RX_DN8")
	)
	(segment
		(start 21.999956 -5.747004)
		(end 21.999956 -3.495548)
		(width 0.1397)
		(layer "F.Cu")
		(net "P2E_CPU_ETH10G_RX_DN8")
	)
	(segment
		(start 21.999448 -16.649954)
		(end 21.999448 -17.134586)
		(width 0.1397)
		(layer "F.Cu")
		(net "P2E_CPU_ETH10G_RX_DN8")
	)
	(segment
		(start 22.632162 -17.43456)
		(end 22.860762 -17.20596)
		(width 0.1397)
		(layer "F.Cu")
		(net "P2E_CPU_ETH10G_RX_DN8")
	)
	(segment
		(start 21.999702 -16.649954)
		(end 21.999448 -16.649954)
		(width 0.1397)
		(layer "F.Cu")
		(net "P2E_CPU_ETH10G_RX_DN8")
	)
	(segment
		(start 22.328632 -14.619732)
		(end 22.328632 -6.07568)
		(width 0.1397)
		(layer "F.Cu")
		(net "P2E_CPU_ETH10G_RX_DN8")
	)
	(segment
		(start 22.328378 -14.619986)
		(end 22.328632 -14.619732)
		(width 0.1397)
		(layer "F.Cu")
		(net "P2E_CPU_ETH10G_RX_DN8")
	)
	(segment
		(start 22.328632 -6.07568)
		(end 21.999956 -5.747004)
		(width 0.1397)
		(layer "F.Cu")
		(net "P2E_CPU_ETH10G_RX_DN8")
	)
	(segment
		(start 22.96414 -18.613882)
		(end 22.96414 -17.587722)
		(width 0.1397)
		(layer "F.Cu")
		(net "P2E_CPU_ETH10G_RX_DP8")
	)
	(segment
		(start 23.000462 -18.650204)
		(end 22.96414 -18.613882)
		(width 0.1397)
		(layer "F.Cu")
		(net "P2E_CPU_ETH10G_RX_DP8")
	)
	(segment
		(start 22.671532 -6.07568)
		(end 22.999954 -5.747258)
		(width 0.1397)
		(layer "F.Cu")
		(net "P2E_CPU_ETH10G_RX_DP8")
	)
	(segment
		(start 23.203662 -17.3482)
		(end 23.203662 -15.01013)
		(width 0.1397)
		(layer "F.Cu")
		(net "P2E_CPU_ETH10G_RX_DP8")
	)
	(segment
		(start 22.96414 -17.587722)
		(end 23.203662 -17.3482)
		(width 0.1397)
		(layer "F.Cu")
		(net "P2E_CPU_ETH10G_RX_DP8")
	)
	(segment
		(start 22.999954 -5.747258)
		(end 22.999954 -3.495548)
		(width 0.1397)
		(layer "F.Cu")
		(net "P2E_CPU_ETH10G_RX_DP8")
	)
	(segment
		(start 23.203662 -15.01013)
		(end 22.671532 -14.478)
		(width 0.1397)
		(layer "F.Cu")
		(net "P2E_CPU_ETH10G_RX_DP8")
	)
	(segment
		(start 22.671532 -14.478)
		(end 22.671532 -6.07568)
		(width 0.1397)
		(layer "F.Cu")
		(net "P2E_CPU_ETH10G_RX_DP8")
	)
	(segment
		(start 18.861532 -15.15237)
		(end 18.32864 -14.619478)
		(width 0.1397)
		(layer "F.Cu")
		(net "P2E_CPU_ETH10G_RX_DN9")
	)
	(segment
		(start 18.000218 -16.649954)
		(end 18.000218 -17.134586)
		(width 0.1397)
		(layer "F.Cu")
		(net "P2E_CPU_ETH10G_RX_DN9")
	)
	(segment
		(start 18.000218 -17.134586)
		(end 18.292572 -17.42694)
		(width 0.1397)
		(layer "F.Cu")
		(net "P2E_CPU_ETH10G_RX_DN9")
	)
	(segment
		(start 18.000472 -16.649954)
		(end 18.000218 -16.649954)
		(width 0.1397)
		(layer "F.Cu")
		(net "P2E_CPU_ETH10G_RX_DN9")
	)
	(segment
		(start 17.999964 -5.747004)
		(end 17.999964 -3.495548)
		(width 0.1397)
		(layer "F.Cu")
		(net "P2E_CPU_ETH10G_RX_DN9")
	)
	(segment
		(start 18.32864 -14.619478)
		(end 18.32864 -6.07568)
		(width 0.1397)
		(layer "F.Cu")
		(net "P2E_CPU_ETH10G_RX_DN9")
	)
	(segment
		(start 18.861532 -17.20596)
		(end 18.861532 -15.15237)
		(width 0.1397)
		(layer "F.Cu")
		(net "P2E_CPU_ETH10G_RX_DN9")
	)
	(segment
		(start 18.32864 -6.07568)
		(end 17.999964 -5.747004)
		(width 0.1397)
		(layer "F.Cu")
		(net "P2E_CPU_ETH10G_RX_DN9")
	)
	(segment
		(start 18.292572 -17.42694)
		(end 18.640552 -17.42694)
		(width 0.1397)
		(layer "F.Cu")
		(net "P2E_CPU_ETH10G_RX_DN9")
	)
	(segment
		(start 18.640552 -17.42694)
		(end 18.861532 -17.20596)
		(width 0.1397)
		(layer "F.Cu")
		(net "P2E_CPU_ETH10G_RX_DN9")
	)
	(segment
		(start 18.9484 -17.604232)
		(end 19.204432 -17.3482)
		(width 0.1397)
		(layer "F.Cu")
		(net "P2E_CPU_ETH10G_RX_DP9")
	)
	(segment
		(start 18.67154 -6.07568)
		(end 18.999962 -5.747258)
		(width 0.1397)
		(layer "F.Cu")
		(net "P2E_CPU_ETH10G_RX_DP9")
	)
	(segment
		(start 18.9484 -18.598642)
		(end 18.9484 -17.604232)
		(width 0.1397)
		(layer "F.Cu")
		(net "P2E_CPU_ETH10G_RX_DP9")
	)
	(segment
		(start 18.67154 -14.477238)
		(end 18.67154 -6.07568)
		(width 0.1397)
		(layer "F.Cu")
		(net "P2E_CPU_ETH10G_RX_DP9")
	)
	(segment
		(start 19.204432 -15.01013)
		(end 18.67154 -14.477238)
		(width 0.1397)
		(layer "F.Cu")
		(net "P2E_CPU_ETH10G_RX_DP9")
	)
	(segment
		(start 18.999962 -18.650204)
		(end 18.9484 -18.598642)
		(width 0.1397)
		(layer "F.Cu")
		(net "P2E_CPU_ETH10G_RX_DP9")
	)
	(segment
		(start 18.999962 -5.747258)
		(end 18.999962 -3.495548)
		(width 0.1397)
		(layer "F.Cu")
		(net "P2E_CPU_ETH10G_RX_DP9")
	)
	(segment
		(start 19.204432 -17.3482)
		(end 19.204432 -15.01013)
		(width 0.1397)
		(layer "F.Cu")
		(net "P2E_CPU_ETH10G_RX_DP9")
	)
	(segment
		(start 13.999972 -16.649954)
		(end 13.999718 -16.649954)
		(width 0.1397)
		(layer "F.Cu")
		(net "P2E_CPU_ETH10G_RX_DN10")
	)
	(segment
		(start 13.999718 -16.649954)
		(end 13.999718 -17.133316)
		(width 0.1397)
		(layer "F.Cu")
		(net "P2E_CPU_ETH10G_RX_DN10")
	)
	(segment
		(start 14.328648 -6.07568)
		(end 13.999972 -5.747004)
		(width 0.1397)
		(layer "F.Cu")
		(net "P2E_CPU_ETH10G_RX_DN10")
	)
	(segment
		(start 13.999718 -17.133316)
		(end 14.285722 -17.41932)
		(width 0.1397)
		(layer "F.Cu")
		(net "P2E_CPU_ETH10G_RX_DN10")
	)
	(segment
		(start 14.285722 -17.41932)
		(end 14.648942 -17.41932)
		(width 0.1397)
		(layer "F.Cu")
		(net "P2E_CPU_ETH10G_RX_DN10")
	)
	(segment
		(start 14.328648 -14.661388)
		(end 14.328648 -6.07568)
		(width 0.1397)
		(layer "F.Cu")
		(net "P2E_CPU_ETH10G_RX_DN10")
	)
	(segment
		(start 14.862302 -17.20596)
		(end 14.862302 -15.195042)
		(width 0.1397)
		(layer "F.Cu")
		(net "P2E_CPU_ETH10G_RX_DN10")
	)
	(segment
		(start 14.648942 -17.41932)
		(end 14.862302 -17.20596)
		(width 0.1397)
		(layer "F.Cu")
		(net "P2E_CPU_ETH10G_RX_DN10")
	)
	(segment
		(start 13.999972 -5.747004)
		(end 13.999972 -3.495548)
		(width 0.1397)
		(layer "F.Cu")
		(net "P2E_CPU_ETH10G_RX_DN10")
	)
	(segment
		(start 14.862302 -15.195042)
		(end 14.328648 -14.661388)
		(width 0.1397)
		(layer "F.Cu")
		(net "P2E_CPU_ETH10G_RX_DN10")
	)
	(segment
		(start 14.671548 -13.18006)
		(end 14.672818 -13.17879)
		(width 0.1397)
		(layer "F.Cu")
		(net "P2E_CPU_ETH10G_RX_DP10")
	)
	(segment
		(start 15.000732 -18.650204)
		(end 15.000478 -18.650204)
		(width 0.1397)
		(layer "F.Cu")
		(net "P2E_CPU_ETH10G_RX_DP10")
	)
	(segment
		(start 14.671548 -6.07568)
		(end 14.99997 -5.747258)
		(width 0.1397)
		(layer "F.Cu")
		(net "P2E_CPU_ETH10G_RX_DP10")
	)
	(segment
		(start 14.672818 -13.11656)
		(end 14.671548 -13.11529)
		(width 0.1397)
		(layer "F.Cu")
		(net "P2E_CPU_ETH10G_RX_DP10")
	)
	(segment
		(start 15.000478 -17.552924)
		(end 15.205202 -17.3482)
		(width 0.1397)
		(layer "F.Cu")
		(net "P2E_CPU_ETH10G_RX_DP10")
	)
	(segment
		(start 14.672818 -13.17879)
		(end 14.672818 -13.11656)
		(width 0.1397)
		(layer "F.Cu")
		(net "P2E_CPU_ETH10G_RX_DP10")
	)
	(segment
		(start 15.205202 -17.3482)
		(end 15.205202 -15.052802)
		(width 0.1397)
		(layer "F.Cu")
		(net "P2E_CPU_ETH10G_RX_DP10")
	)
	(segment
		(start 14.99997 -5.747258)
		(end 14.99997 -3.495548)
		(width 0.1397)
		(layer "F.Cu")
		(net "P2E_CPU_ETH10G_RX_DP10")
	)
	(segment
		(start 14.671548 -14.519148)
		(end 14.671548 -13.18006)
		(width 0.1397)
		(layer "F.Cu")
		(net "P2E_CPU_ETH10G_RX_DP10")
	)
	(segment
		(start 15.205202 -15.052802)
		(end 14.671548 -14.519148)
		(width 0.1397)
		(layer "F.Cu")
		(net "P2E_CPU_ETH10G_RX_DP10")
	)
	(segment
		(start 15.000478 -18.650204)
		(end 15.000478 -17.552924)
		(width 0.1397)
		(layer "F.Cu")
		(net "P2E_CPU_ETH10G_RX_DP10")
	)
	(segment
		(start 14.671548 -13.11529)
		(end 14.671548 -6.07568)
		(width 0.1397)
		(layer "F.Cu")
		(net "P2E_CPU_ETH10G_RX_DP10")
	)
	(segment
		(start 10.863072 -15.15237)
		(end 10.333482 -14.62278)
		(width 0.1397)
		(layer "F.Cu")
		(net "P2E_CPU_ETH10G_RX_DN11")
	)
	(segment
		(start 10.000742 -16.649954)
		(end 10.000488 -16.649954)
		(width 0.1397)
		(layer "F.Cu")
		(net "P2E_CPU_ETH10G_RX_DN11")
	)
	(segment
		(start 10.000488 -17.133316)
		(end 10.301732 -17.43456)
		(width 0.1397)
		(layer "F.Cu")
		(net "P2E_CPU_ETH10G_RX_DN11")
	)
	(segment
		(start 10.863072 -17.20596)
		(end 10.863072 -15.15237)
		(width 0.1397)
		(layer "F.Cu")
		(net "P2E_CPU_ETH10G_RX_DN11")
	)
	(segment
		(start 10.634472 -17.43456)
		(end 10.863072 -17.20596)
		(width 0.1397)
		(layer "F.Cu")
		(net "P2E_CPU_ETH10G_RX_DN11")
	)
	(segment
		(start 10.000488 -16.649954)
		(end 10.000488 -17.133316)
		(width 0.1397)
		(layer "F.Cu")
		(net "P2E_CPU_ETH10G_RX_DN11")
	)
	(segment
		(start 10.301732 -17.43456)
		(end 10.634472 -17.43456)
		(width 0.1397)
		(layer "F.Cu")
		(net "P2E_CPU_ETH10G_RX_DN11")
	)
	(segment
		(start 10.333482 -14.62278)
		(end 10.333482 -6.080506)
		(width 0.1397)
		(layer "F.Cu")
		(net "P2E_CPU_ETH10G_RX_DN11")
	)
	(segment
		(start 9.99998 -5.747004)
		(end 9.99998 -3.495548)
		(width 0.1397)
		(layer "F.Cu")
		(net "P2E_CPU_ETH10G_RX_DN11")
	)
	(segment
		(start 10.333482 -6.080506)
		(end 9.99998 -5.747004)
		(width 0.1397)
		(layer "F.Cu")
		(net "P2E_CPU_ETH10G_RX_DN11")
	)
	(segment
		(start 10.999978 -5.747258)
		(end 10.999978 -3.495548)
		(width 0.1397)
		(layer "F.Cu")
		(net "P2E_CPU_ETH10G_RX_DP11")
	)
	(segment
		(start 11.205972 -15.01013)
		(end 10.676382 -14.48054)
		(width 0.1397)
		(layer "F.Cu")
		(net "P2E_CPU_ETH10G_RX_DP11")
	)
	(segment
		(start 10.9601 -17.594072)
		(end 11.205972 -17.3482)
		(width 0.1397)
		(layer "F.Cu")
		(net "P2E_CPU_ETH10G_RX_DP11")
	)
	(segment
		(start 11.000232 -18.650204)
		(end 10.9601 -18.610072)
		(width 0.1397)
		(layer "F.Cu")
		(net "P2E_CPU_ETH10G_RX_DP11")
	)
	(segment
		(start 11.205972 -17.3482)
		(end 11.205972 -15.01013)
		(width 0.1397)
		(layer "F.Cu")
		(net "P2E_CPU_ETH10G_RX_DP11")
	)
	(segment
		(start 10.9601 -18.610072)
		(end 10.9601 -17.594072)
		(width 0.1397)
		(layer "F.Cu")
		(net "P2E_CPU_ETH10G_RX_DP11")
	)
	(segment
		(start 10.676382 -14.48054)
		(end 10.676382 -6.070854)
		(width 0.1397)
		(layer "F.Cu")
		(net "P2E_CPU_ETH10G_RX_DP11")
	)
	(segment
		(start 10.676382 -6.070854)
		(end 10.999978 -5.747258)
		(width 0.1397)
		(layer "F.Cu")
		(net "P2E_CPU_ETH10G_RX_DP11")
	)
	(segment
		(start 8.000492 -23.149814)
		(end 8.000238 -23.149814)
		(width 0.1397)
		(layer "B.Cu")
		(net "P2E_CPU_ETH10G_TX_DN11")
	)
	(segment
		(start 9.711182 -9.34212)
		(end 8.834882 -8.46582)
		(width 0.1397)
		(layer "B.Cu")
		(net "P2E_CPU_ETH10G_TX_DN11")
	)
	(segment
		(start 7.999984 -5.747258)
		(end 7.999984 -3.114548)
		(width 0.1397)
		(layer "B.Cu")
		(net "P2E_CPU_ETH10G_TX_DN11")
	)
	(segment
		(start 8.834882 -15.32636)
		(end 9.711182 -14.45006)
		(width 0.1397)
		(layer "B.Cu")
		(net "P2E_CPU_ETH10G_TX_DN11")
	)
	(segment
		(start 8.834882 -7.125716)
		(end 8.328406 -6.61924)
		(width 0.1397)
		(layer "B.Cu")
		(net "P2E_CPU_ETH10G_TX_DN11")
	)
	(segment
		(start 8.834882 -17.02816)
		(end 8.834882 -15.32636)
		(width 0.1397)
		(layer "B.Cu")
		(net "P2E_CPU_ETH10G_TX_DN11")
	)
	(segment
		(start 8.328406 -6.61924)
		(end 8.328406 -6.07568)
		(width 0.1397)
		(layer "B.Cu")
		(net "P2E_CPU_ETH10G_TX_DN11")
	)
	(segment
		(start 9.711182 -14.45006)
		(end 9.711182 -9.34212)
		(width 0.1397)
		(layer "B.Cu")
		(net "P2E_CPU_ETH10G_TX_DN11")
	)
	(segment
		(start 8.187182 -22.1996)
		(end 7.882382 -21.8948)
		(width 0.1397)
		(layer "B.Cu")
		(net "P2E_CPU_ETH10G_TX_DN11")
	)
	(segment
		(start 7.882382 -17.98066)
		(end 8.834882 -17.02816)
		(width 0.1397)
		(layer "B.Cu")
		(net "P2E_CPU_ETH10G_TX_DN11")
	)
	(segment
		(start 8.834882 -8.46582)
		(end 8.834882 -7.125716)
		(width 0.1397)
		(layer "B.Cu")
		(net "P2E_CPU_ETH10G_TX_DN11")
	)
	(segment
		(start 8.328406 -6.07568)
		(end 7.999984 -5.747258)
		(width 0.1397)
		(layer "B.Cu")
		(net "P2E_CPU_ETH10G_TX_DN11")
	)
	(segment
		(start 8.187182 -22.96287)
		(end 8.187182 -22.1996)
		(width 0.1397)
		(layer "B.Cu")
		(net "P2E_CPU_ETH10G_TX_DN11")
	)
	(segment
		(start 7.882382 -21.8948)
		(end 7.882382 -17.98066)
		(width 0.1397)
		(layer "B.Cu")
		(net "P2E_CPU_ETH10G_TX_DN11")
	)
	(segment
		(start 8.000238 -23.149814)
		(end 8.187182 -22.96287)
		(width 0.1397)
		(layer "B.Cu")
		(net "P2E_CPU_ETH10G_TX_DN11")
	)
	(segment
		(start 8.225282 -21.75256)
		(end 8.225282 -18.1229)
		(width 0.1397)
		(layer "B.Cu")
		(net "P2E_CPU_ETH10G_TX_DP11")
	)
	(segment
		(start 9.177782 -17.1704)
		(end 9.177782 -15.4686)
		(width 0.1397)
		(layer "B.Cu")
		(net "P2E_CPU_ETH10G_TX_DP11")
	)
	(segment
		(start 10.054082 -14.5923)
		(end 10.054082 -9.19988)
		(width 0.1397)
		(layer "B.Cu")
		(net "P2E_CPU_ETH10G_TX_DP11")
	)
	(segment
		(start 8.671306 -6.07568)
		(end 8.999982 -5.747004)
		(width 0.1397)
		(layer "B.Cu")
		(net "P2E_CPU_ETH10G_TX_DP11")
	)
	(segment
		(start 10.054082 -9.19988)
		(end 9.177782 -8.32358)
		(width 0.1397)
		(layer "B.Cu")
		(net "P2E_CPU_ETH10G_TX_DP11")
	)
	(segment
		(start 8.225282 -18.1229)
		(end 9.177782 -17.1704)
		(width 0.1397)
		(layer "B.Cu")
		(net "P2E_CPU_ETH10G_TX_DP11")
	)
	(segment
		(start 9.177782 -8.32358)
		(end 9.177782 -6.983476)
		(width 0.1397)
		(layer "B.Cu")
		(net "P2E_CPU_ETH10G_TX_DP11")
	)
	(segment
		(start 8.671306 -6.477)
		(end 8.671306 -6.07568)
		(width 0.1397)
		(layer "B.Cu")
		(net "P2E_CPU_ETH10G_TX_DP11")
	)
	(segment
		(start 8.999728 -21.793454)
		(end 8.796782 -21.9964)
		(width 0.1397)
		(layer "B.Cu")
		(net "P2E_CPU_ETH10G_TX_DP11")
	)
	(segment
		(start 8.999982 -5.747004)
		(end 8.999982 -3.114548)
		(width 0.1397)
		(layer "B.Cu")
		(net "P2E_CPU_ETH10G_TX_DP11")
	)
	(segment
		(start 8.796782 -21.9964)
		(end 8.469122 -21.9964)
		(width 0.1397)
		(layer "B.Cu")
		(net "P2E_CPU_ETH10G_TX_DP11")
	)
	(segment
		(start 8.999982 -21.149564)
		(end 8.999728 -21.149564)
		(width 0.1397)
		(layer "B.Cu")
		(net "P2E_CPU_ETH10G_TX_DP11")
	)
	(segment
		(start 8.469122 -21.9964)
		(end 8.225282 -21.75256)
		(width 0.1397)
		(layer "B.Cu")
		(net "P2E_CPU_ETH10G_TX_DP11")
	)
	(segment
		(start 9.177782 -15.4686)
		(end 10.054082 -14.5923)
		(width 0.1397)
		(layer "B.Cu")
		(net "P2E_CPU_ETH10G_TX_DP11")
	)
	(segment
		(start 9.177782 -6.983476)
		(end 8.671306 -6.477)
		(width 0.1397)
		(layer "B.Cu")
		(net "P2E_CPU_ETH10G_TX_DP11")
	)
	(segment
		(start 8.999728 -21.149564)
		(end 8.999728 -21.793454)
		(width 0.1397)
		(layer "B.Cu")
		(net "P2E_CPU_ETH10G_TX_DP11")
	)
	(segment
		(start 12.187682 -22.96287)
		(end 12.187682 -22.1996)
		(width 0.1397)
		(layer "B.Cu")
		(net "P2E_CPU_ETH10G_TX_DN10")
	)
	(segment
		(start 11.882882 -21.8948)
		(end 11.882882 -18.0086)
		(width 0.1397)
		(layer "B.Cu")
		(net "P2E_CPU_ETH10G_TX_DN10")
	)
	(segment
		(start 12.835382 -15.748)
		(end 12.328652 -15.24127)
		(width 0.1397)
		(layer "B.Cu")
		(net "P2E_CPU_ETH10G_TX_DN10")
	)
	(segment
		(start 12.328652 -15.24127)
		(end 12.328652 -6.07568)
		(width 0.1397)
		(layer "B.Cu")
		(net "P2E_CPU_ETH10G_TX_DN10")
	)
	(segment
		(start 12.187682 -22.1996)
		(end 11.882882 -21.8948)
		(width 0.1397)
		(layer "B.Cu")
		(net "P2E_CPU_ETH10G_TX_DN10")
	)
	(segment
		(start 11.999722 -23.149814)
		(end 12.000738 -23.149814)
		(width 0.1397)
		(layer "B.Cu")
		(net "P2E_CPU_ETH10G_TX_DN10")
	)
	(segment
		(start 11.999976 -5.747004)
		(end 11.999976 -3.114548)
		(width 0.1397)
		(layer "B.Cu")
		(net "P2E_CPU_ETH10G_TX_DN10")
	)
	(segment
		(start 11.882882 -18.0086)
		(end 12.835382 -17.0561)
		(width 0.1397)
		(layer "B.Cu")
		(net "P2E_CPU_ETH10G_TX_DN10")
	)
	(segment
		(start 12.328652 -6.07568)
		(end 11.999976 -5.747004)
		(width 0.1397)
		(layer "B.Cu")
		(net "P2E_CPU_ETH10G_TX_DN10")
	)
	(segment
		(start 12.000738 -23.149814)
		(end 12.187682 -22.96287)
		(width 0.1397)
		(layer "B.Cu")
		(net "P2E_CPU_ETH10G_TX_DN10")
	)
	(segment
		(start 12.835382 -17.0561)
		(end 12.835382 -15.748)
		(width 0.1397)
		(layer "B.Cu")
		(net "P2E_CPU_ETH10G_TX_DN10")
	)
	(segment
		(start 13.000228 -21.149564)
		(end 13.000228 -21.793454)
		(width 0.1397)
		(layer "B.Cu")
		(net "P2E_CPU_ETH10G_TX_DP10")
	)
	(segment
		(start 12.225782 -18.15084)
		(end 13.178282 -17.19834)
		(width 0.1397)
		(layer "B.Cu")
		(net "P2E_CPU_ETH10G_TX_DP10")
	)
	(segment
		(start 13.000482 -21.149564)
		(end 13.000228 -21.149564)
		(width 0.1397)
		(layer "B.Cu")
		(net "P2E_CPU_ETH10G_TX_DP10")
	)
	(segment
		(start 12.225782 -21.75256)
		(end 12.225782 -18.15084)
		(width 0.1397)
		(layer "B.Cu")
		(net "P2E_CPU_ETH10G_TX_DP10")
	)
	(segment
		(start 13.178282 -17.19834)
		(end 13.178282 -15.60576)
		(width 0.1397)
		(layer "B.Cu")
		(net "P2E_CPU_ETH10G_TX_DP10")
	)
	(segment
		(start 12.797282 -21.9964)
		(end 12.469622 -21.9964)
		(width 0.1397)
		(layer "B.Cu")
		(net "P2E_CPU_ETH10G_TX_DP10")
	)
	(segment
		(start 12.469622 -21.9964)
		(end 12.225782 -21.75256)
		(width 0.1397)
		(layer "B.Cu")
		(net "P2E_CPU_ETH10G_TX_DP10")
	)
	(segment
		(start 12.671552 -15.09903)
		(end 12.671552 -6.07568)
		(width 0.1397)
		(layer "B.Cu")
		(net "P2E_CPU_ETH10G_TX_DP10")
	)
	(segment
		(start 13.178282 -15.60576)
		(end 12.671552 -15.09903)
		(width 0.1397)
		(layer "B.Cu")
		(net "P2E_CPU_ETH10G_TX_DP10")
	)
	(segment
		(start 13.000228 -21.793454)
		(end 12.797282 -21.9964)
		(width 0.1397)
		(layer "B.Cu")
		(net "P2E_CPU_ETH10G_TX_DP10")
	)
	(segment
		(start 12.999974 -5.747258)
		(end 12.999974 -3.114548)
		(width 0.1397)
		(layer "B.Cu")
		(net "P2E_CPU_ETH10G_TX_DP10")
	)
	(segment
		(start 12.671552 -6.07568)
		(end 12.999974 -5.747258)
		(width 0.1397)
		(layer "B.Cu")
		(net "P2E_CPU_ETH10G_TX_DP10")
	)
	(segment
		(start 16.834612 -17.0561)
		(end 16.834612 -15.76197)
		(width 0.1397)
		(layer "B.Cu")
		(net "P2E_CPU_ETH10G_TX_DN9")
	)
	(segment
		(start 16.186912 -22.96287)
		(end 16.186912 -22.1996)
		(width 0.1397)
		(layer "B.Cu")
		(net "P2E_CPU_ETH10G_TX_DN9")
	)
	(segment
		(start 15.882112 -18.0086)
		(end 16.834612 -17.0561)
		(width 0.1397)
		(layer "B.Cu")
		(net "P2E_CPU_ETH10G_TX_DN9")
	)
	(segment
		(start 16.328644 -15.256002)
		(end 16.328644 -6.07568)
		(width 0.1397)
		(layer "B.Cu")
		(net "P2E_CPU_ETH10G_TX_DN9")
	)
	(segment
		(start 15.999968 -5.747004)
		(end 15.999968 -3.114548)
		(width 0.1397)
		(layer "B.Cu")
		(net "P2E_CPU_ETH10G_TX_DN9")
	)
	(segment
		(start 16.328644 -6.07568)
		(end 15.999968 -5.747004)
		(width 0.1397)
		(layer "B.Cu")
		(net "P2E_CPU_ETH10G_TX_DN9")
	)
	(segment
		(start 16.000222 -23.14956)
		(end 16.186912 -22.96287)
		(width 0.1397)
		(layer "B.Cu")
		(net "P2E_CPU_ETH10G_TX_DN9")
	)
	(segment
		(start 16.186912 -22.1996)
		(end 15.882112 -21.8948)
		(width 0.1397)
		(layer "B.Cu")
		(net "P2E_CPU_ETH10G_TX_DN9")
	)
	(segment
		(start 16.834612 -15.76197)
		(end 16.328644 -15.256002)
		(width 0.1397)
		(layer "B.Cu")
		(net "P2E_CPU_ETH10G_TX_DN9")
	)
	(segment
		(start 16.000222 -23.149814)
		(end 16.000222 -23.14956)
		(width 0.1397)
		(layer "B.Cu")
		(net "P2E_CPU_ETH10G_TX_DN9")
	)
	(segment
		(start 15.882112 -21.8948)
		(end 15.882112 -18.0086)
		(width 0.1397)
		(layer "B.Cu")
		(net "P2E_CPU_ETH10G_TX_DN9")
	)
	(segment
		(start 16.225012 -21.75256)
		(end 16.225012 -18.15084)
		(width 0.1397)
		(layer "B.Cu")
		(net "P2E_CPU_ETH10G_TX_DP9")
	)
	(segment
		(start 16.671544 -6.07568)
		(end 16.999966 -5.747258)
		(width 0.1397)
		(layer "B.Cu")
		(net "P2E_CPU_ETH10G_TX_DP9")
	)
	(segment
		(start 16.999712 -21.149564)
		(end 16.999458 -21.149564)
		(width 0.1397)
		(layer "B.Cu")
		(net "P2E_CPU_ETH10G_TX_DP9")
	)
	(segment
		(start 16.796512 -21.9964)
		(end 16.468852 -21.9964)
		(width 0.1397)
		(layer "B.Cu")
		(net "P2E_CPU_ETH10G_TX_DP9")
	)
	(segment
		(start 16.999458 -21.793454)
		(end 16.796512 -21.9964)
		(width 0.1397)
		(layer "B.Cu")
		(net "P2E_CPU_ETH10G_TX_DP9")
	)
	(segment
		(start 17.177512 -15.61973)
		(end 16.671544 -15.113762)
		(width 0.1397)
		(layer "B.Cu")
		(net "P2E_CPU_ETH10G_TX_DP9")
	)
	(segment
		(start 16.999458 -21.149564)
		(end 16.999458 -21.793454)
		(width 0.1397)
		(layer "B.Cu")
		(net "P2E_CPU_ETH10G_TX_DP9")
	)
	(segment
		(start 16.225012 -18.15084)
		(end 17.177512 -17.19834)
		(width 0.1397)
		(layer "B.Cu")
		(net "P2E_CPU_ETH10G_TX_DP9")
	)
	(segment
		(start 16.671544 -15.113762)
		(end 16.671544 -6.07568)
		(width 0.1397)
		(layer "B.Cu")
		(net "P2E_CPU_ETH10G_TX_DP9")
	)
	(segment
		(start 16.468852 -21.9964)
		(end 16.225012 -21.75256)
		(width 0.1397)
		(layer "B.Cu")
		(net "P2E_CPU_ETH10G_TX_DP9")
	)
	(segment
		(start 17.177512 -17.19834)
		(end 17.177512 -15.61973)
		(width 0.1397)
		(layer "B.Cu")
		(net "P2E_CPU_ETH10G_TX_DP9")
	)
	(segment
		(start 16.999966 -5.747258)
		(end 16.999966 -3.114548)
		(width 0.1397)
		(layer "B.Cu")
		(net "P2E_CPU_ETH10G_TX_DP9")
	)
	(segment
		(start 20.186142 -22.964394)
		(end 20.186142 -22.1996)
		(width 0.1397)
		(layer "B.Cu")
		(net "P2E_CPU_ETH10G_TX_DN8")
	)
	(segment
		(start 19.881342 -18.0086)
		(end 20.833842 -17.0561)
		(width 0.1397)
		(layer "B.Cu")
		(net "P2E_CPU_ETH10G_TX_DN8")
	)
	(segment
		(start 20.186142 -22.1996)
		(end 19.881342 -21.8948)
		(width 0.1397)
		(layer "B.Cu")
		(net "P2E_CPU_ETH10G_TX_DN8")
	)
	(segment
		(start 19.881342 -21.8948)
		(end 19.881342 -18.0086)
		(width 0.1397)
		(layer "B.Cu")
		(net "P2E_CPU_ETH10G_TX_DN8")
	)
	(segment
		(start 20.000722 -23.149814)
		(end 20.186142 -22.964394)
		(width 0.1397)
		(layer "B.Cu")
		(net "P2E_CPU_ETH10G_TX_DN8")
	)
	(segment
		(start 20.328636 -6.07568)
		(end 19.99996 -5.747004)
		(width 0.1397)
		(layer "B.Cu")
		(net "P2E_CPU_ETH10G_TX_DN8")
	)
	(segment
		(start 20.833842 -17.0561)
		(end 20.833842 -15.211806)
		(width 0.1397)
		(layer "B.Cu")
		(net "P2E_CPU_ETH10G_TX_DN8")
	)
	(segment
		(start 19.99996 -5.747004)
		(end 19.99996 -3.114548)
		(width 0.1397)
		(layer "B.Cu")
		(net "P2E_CPU_ETH10G_TX_DN8")
	)
	(segment
		(start 20.328636 -14.7066)
		(end 20.328636 -6.07568)
		(width 0.1397)
		(layer "B.Cu")
		(net "P2E_CPU_ETH10G_TX_DN8")
	)
	(segment
		(start 20.833842 -15.211806)
		(end 20.328636 -14.7066)
		(width 0.1397)
		(layer "B.Cu")
		(net "P2E_CPU_ETH10G_TX_DN8")
	)
	(segment
		(start 20.671536 -14.56436)
		(end 20.671536 -6.07568)
		(width 0.1397)
		(layer "B.Cu")
		(net "P2E_CPU_ETH10G_TX_DP8")
	)
	(segment
		(start 21.176742 -17.19834)
		(end 21.176742 -15.069566)
		(width 0.1397)
		(layer "B.Cu")
		(net "P2E_CPU_ETH10G_TX_DP8")
	)
	(segment
		(start 20.224242 -18.15084)
		(end 21.176742 -17.19834)
		(width 0.1397)
		(layer "B.Cu")
		(net "P2E_CPU_ETH10G_TX_DP8")
	)
	(segment
		(start 20.998688 -21.793454)
		(end 20.795742 -21.9964)
		(width 0.1397)
		(layer "B.Cu")
		(net "P2E_CPU_ETH10G_TX_DP8")
	)
	(segment
		(start 20.671536 -6.07568)
		(end 20.999958 -5.747258)
		(width 0.1397)
		(layer "B.Cu")
		(net "P2E_CPU_ETH10G_TX_DP8")
	)
	(segment
		(start 20.999958 -5.747258)
		(end 20.999958 -3.114548)
		(width 0.1397)
		(layer "B.Cu")
		(net "P2E_CPU_ETH10G_TX_DP8")
	)
	(segment
		(start 21.176742 -15.069566)
		(end 20.671536 -14.56436)
		(width 0.1397)
		(layer "B.Cu")
		(net "P2E_CPU_ETH10G_TX_DP8")
	)
	(segment
		(start 20.795742 -21.9964)
		(end 20.468082 -21.9964)
		(width 0.1397)
		(layer "B.Cu")
		(net "P2E_CPU_ETH10G_TX_DP8")
	)
	(segment
		(start 20.468082 -21.9964)
		(end 20.224242 -21.75256)
		(width 0.1397)
		(layer "B.Cu")
		(net "P2E_CPU_ETH10G_TX_DP8")
	)
	(segment
		(start 20.998688 -21.149564)
		(end 20.998688 -21.793454)
		(width 0.1397)
		(layer "B.Cu")
		(net "P2E_CPU_ETH10G_TX_DP8")
	)
	(segment
		(start 20.224242 -21.75256)
		(end 20.224242 -18.15084)
		(width 0.1397)
		(layer "B.Cu")
		(net "P2E_CPU_ETH10G_TX_DP8")
	)
	(segment
		(start 21.000212 -21.149564)
		(end 20.998688 -21.149564)
		(width 0.1397)
		(layer "B.Cu")
		(net "P2E_CPU_ETH10G_TX_DP8")
	)
	(segment
		(start 24.833072 -17.0561)
		(end 24.833072 -16.021812)
		(width 0.1397)
		(layer "B.Cu")
		(net "P2E_CPU_SAS_TX_DN7")
	)
	(segment
		(start 24.668988 -9.951212)
		(end 24.328628 -9.610852)
		(width 0.1397)
		(layer "B.Cu")
		(net "P2E_CPU_SAS_TX_DN7")
	)
	(segment
		(start 24.328628 -6.07568)
		(end 23.999952 -5.747004)
		(width 0.1397)
		(layer "B.Cu")
		(net "P2E_CPU_SAS_TX_DN7")
	)
	(segment
		(start 23.80488 -14.99362)
		(end 23.80488 -14.457172)
		(width 0.1397)
		(layer "B.Cu")
		(net "P2E_CPU_SAS_TX_DN7")
	)
	(segment
		(start 24.14524 -13.558012)
		(end 23.80488 -13.217652)
		(width 0.1397)
		(layer "B.Cu")
		(net "P2E_CPU_SAS_TX_DN7")
	)
	(segment
		(start 24.712676 -10.510012)
		(end 24.852376 -10.370312)
		(width 0.1397)
		(layer "B.Cu")
		(net "P2E_CPU_SAS_TX_DN7")
	)
	(segment
		(start 24.712676 -12.313412)
		(end 24.852376 -12.173712)
		(width 0.1397)
		(layer "B.Cu")
		(net "P2E_CPU_SAS_TX_DN7")
	)
	(segment
		(start 23.80488 -13.217652)
		(end 23.80488 -12.653772)
		(width 0.1397)
		(layer "B.Cu")
		(net "P2E_CPU_SAS_TX_DN7")
	)
	(segment
		(start 24.185372 -22.96287)
		(end 24.185372 -22.1996)
		(width 0.1397)
		(layer "B.Cu")
		(net "P2E_CPU_SAS_TX_DN7")
	)
	(segment
		(start 23.999952 -5.747004)
		(end 23.999952 -3.114548)
		(width 0.1397)
		(layer "B.Cu")
		(net "P2E_CPU_SAS_TX_DN7")
	)
	(segment
		(start 24.852376 -10.090912)
		(end 24.712676 -9.951212)
		(width 0.1397)
		(layer "B.Cu")
		(net "P2E_CPU_SAS_TX_DN7")
	)
	(segment
		(start 24.14524 -10.510012)
		(end 24.712676 -10.510012)
		(width 0.1397)
		(layer "B.Cu")
		(net "P2E_CPU_SAS_TX_DN7")
	)
	(segment
		(start 24.14524 -14.116812)
		(end 24.712676 -14.116812)
		(width 0.1397)
		(layer "B.Cu")
		(net "P2E_CPU_SAS_TX_DN7")
	)
	(segment
		(start 24.14524 -11.754612)
		(end 23.80488 -11.414252)
		(width 0.1397)
		(layer "B.Cu")
		(net "P2E_CPU_SAS_TX_DN7")
	)
	(segment
		(start 23.80488 -11.414252)
		(end 23.80488 -10.850372)
		(width 0.1397)
		(layer "B.Cu")
		(net "P2E_CPU_SAS_TX_DN7")
	)
	(segment
		(start 23.80488 -14.457172)
		(end 24.14524 -14.116812)
		(width 0.1397)
		(layer "B.Cu")
		(net "P2E_CPU_SAS_TX_DN7")
	)
	(segment
		(start 24.852376 -13.977112)
		(end 24.852376 -13.697712)
		(width 0.1397)
		(layer "B.Cu")
		(net "P2E_CPU_SAS_TX_DN7")
	)
	(segment
		(start 24.852376 -10.370312)
		(end 24.852376 -10.090912)
		(width 0.1397)
		(layer "B.Cu")
		(net "P2E_CPU_SAS_TX_DN7")
	)
	(segment
		(start 24.852376 -12.173712)
		(end 24.852376 -11.894312)
		(width 0.1397)
		(layer "B.Cu")
		(net "P2E_CPU_SAS_TX_DN7")
	)
	(segment
		(start 24.328628 -9.610852)
		(end 24.328628 -6.07568)
		(width 0.1397)
		(layer "B.Cu")
		(net "P2E_CPU_SAS_TX_DN7")
	)
	(segment
		(start 23.880572 -18.0086)
		(end 24.833072 -17.0561)
		(width 0.1397)
		(layer "B.Cu")
		(net "P2E_CPU_SAS_TX_DN7")
	)
	(segment
		(start 23.880572 -21.8948)
		(end 23.880572 -18.0086)
		(width 0.1397)
		(layer "B.Cu")
		(net "P2E_CPU_SAS_TX_DN7")
	)
	(segment
		(start 23.998428 -23.149814)
		(end 24.185372 -22.96287)
		(width 0.1397)
		(layer "B.Cu")
		(net "P2E_CPU_SAS_TX_DN7")
	)
	(segment
		(start 24.712676 -13.558012)
		(end 24.14524 -13.558012)
		(width 0.1397)
		(layer "B.Cu")
		(net "P2E_CPU_SAS_TX_DN7")
	)
	(segment
		(start 23.80488 -10.850372)
		(end 24.14524 -10.510012)
		(width 0.1397)
		(layer "B.Cu")
		(net "P2E_CPU_SAS_TX_DN7")
	)
	(segment
		(start 24.712676 -11.754612)
		(end 24.14524 -11.754612)
		(width 0.1397)
		(layer "B.Cu")
		(net "P2E_CPU_SAS_TX_DN7")
	)
	(segment
		(start 24.712676 -9.951212)
		(end 24.668988 -9.951212)
		(width 0.1397)
		(layer "B.Cu")
		(net "P2E_CPU_SAS_TX_DN7")
	)
	(segment
		(start 24.14524 -12.313412)
		(end 24.712676 -12.313412)
		(width 0.1397)
		(layer "B.Cu")
		(net "P2E_CPU_SAS_TX_DN7")
	)
	(segment
		(start 23.80488 -12.653772)
		(end 24.14524 -12.313412)
		(width 0.1397)
		(layer "B.Cu")
		(net "P2E_CPU_SAS_TX_DN7")
	)
	(segment
		(start 24.712676 -14.116812)
		(end 24.852376 -13.977112)
		(width 0.1397)
		(layer "B.Cu")
		(net "P2E_CPU_SAS_TX_DN7")
	)
	(segment
		(start 24.833072 -16.021812)
		(end 23.80488 -14.99362)
		(width 0.1397)
		(layer "B.Cu")
		(net "P2E_CPU_SAS_TX_DN7")
	)
	(segment
		(start 23.999952 -23.149814)
		(end 23.998428 -23.149814)
		(width 0.1397)
		(layer "B.Cu")
		(net "P2E_CPU_SAS_TX_DN7")
	)
	(segment
		(start 24.852376 -13.697712)
		(end 24.712676 -13.558012)
		(width 0.1397)
		(layer "B.Cu")
		(net "P2E_CPU_SAS_TX_DN7")
	)
	(segment
		(start 24.185372 -22.1996)
		(end 23.880572 -21.8948)
		(width 0.1397)
		(layer "B.Cu")
		(net "P2E_CPU_SAS_TX_DN7")
	)
	(segment
		(start 24.852376 -11.894312)
		(end 24.712676 -11.754612)
		(width 0.1397)
		(layer "B.Cu")
		(net "P2E_CPU_SAS_TX_DN7")
	)
	(segment
		(start 24.794972 -21.9964)
		(end 24.467312 -21.9964)
		(width 0.1397)
		(layer "B.Cu")
		(net "P2E_CPU_SAS_TX_DP7")
	)
	(segment
		(start 24.671528 -6.07568)
		(end 24.99995 -5.747258)
		(width 0.1397)
		(layer "B.Cu")
		(net "P2E_CPU_SAS_TX_DP7")
	)
	(segment
		(start 24.28748 -13.215112)
		(end 24.14778 -13.075412)
		(width 0.1397)
		(layer "B.Cu")
		(net "P2E_CPU_SAS_TX_DP7")
	)
	(segment
		(start 24.223472 -18.15084)
		(end 25.175972 -17.19834)
		(width 0.1397)
		(layer "B.Cu")
		(net "P2E_CPU_SAS_TX_DP7")
	)
	(segment
		(start 24.854916 -9.608312)
		(end 24.811228 -9.608312)
		(width 0.1397)
		(layer "B.Cu")
		(net "P2E_CPU_SAS_TX_DP7")
	)
	(segment
		(start 25.000712 -21.149564)
		(end 24.997918 -21.149564)
		(width 0.1397)
		(layer "B.Cu")
		(net "P2E_CPU_SAS_TX_DP7")
	)
	(segment
		(start 24.997918 -21.793454)
		(end 24.794972 -21.9964)
		(width 0.1397)
		(layer "B.Cu")
		(net "P2E_CPU_SAS_TX_DP7")
	)
	(segment
		(start 24.854916 -10.852912)
		(end 25.195276 -10.512552)
		(width 0.1397)
		(layer "B.Cu")
		(net "P2E_CPU_SAS_TX_DP7")
	)
	(segment
		(start 25.195276 -14.119352)
		(end 25.195276 -13.555472)
		(width 0.1397)
		(layer "B.Cu")
		(net "P2E_CPU_SAS_TX_DP7")
	)
	(segment
		(start 24.99995 -5.747258)
		(end 24.99995 -3.114548)
		(width 0.1397)
		(layer "B.Cu")
		(net "P2E_CPU_SAS_TX_DP7")
	)
	(segment
		(start 24.28748 -10.852912)
		(end 24.854916 -10.852912)
		(width 0.1397)
		(layer "B.Cu")
		(net "P2E_CPU_SAS_TX_DP7")
	)
	(segment
		(start 24.14778 -11.272012)
		(end 24.14778 -10.992612)
		(width 0.1397)
		(layer "B.Cu")
		(net "P2E_CPU_SAS_TX_DP7")
	)
	(segment
		(start 24.854916 -13.215112)
		(end 24.28748 -13.215112)
		(width 0.1397)
		(layer "B.Cu")
		(net "P2E_CPU_SAS_TX_DP7")
	)
	(segment
		(start 24.28748 -12.656312)
		(end 24.854916 -12.656312)
		(width 0.1397)
		(layer "B.Cu")
		(net "P2E_CPU_SAS_TX_DP7")
	)
	(segment
		(start 25.175972 -17.19834)
		(end 25.175972 -15.879572)
		(width 0.1397)
		(layer "B.Cu")
		(net "P2E_CPU_SAS_TX_DP7")
	)
	(segment
		(start 24.14778 -14.85138)
		(end 24.14778 -14.599412)
		(width 0.1397)
		(layer "B.Cu")
		(net "P2E_CPU_SAS_TX_DP7")
	)
	(segment
		(start 25.195276 -9.948672)
		(end 24.854916 -9.608312)
		(width 0.1397)
		(layer "B.Cu")
		(net "P2E_CPU_SAS_TX_DP7")
	)
	(segment
		(start 24.854916 -11.411712)
		(end 24.28748 -11.411712)
		(width 0.1397)
		(layer "B.Cu")
		(net "P2E_CPU_SAS_TX_DP7")
	)
	(segment
		(start 24.28748 -11.411712)
		(end 24.14778 -11.272012)
		(width 0.1397)
		(layer "B.Cu")
		(net "P2E_CPU_SAS_TX_DP7")
	)
	(segment
		(start 24.854916 -12.656312)
		(end 25.195276 -12.315952)
		(width 0.1397)
		(layer "B.Cu")
		(net "P2E_CPU_SAS_TX_DP7")
	)
	(segment
		(start 24.14778 -14.599412)
		(end 24.28748 -14.459712)
		(width 0.1397)
		(layer "B.Cu")
		(net "P2E_CPU_SAS_TX_DP7")
	)
	(segment
		(start 25.195276 -11.752072)
		(end 24.854916 -11.411712)
		(width 0.1397)
		(layer "B.Cu")
		(net "P2E_CPU_SAS_TX_DP7")
	)
	(segment
		(start 24.467312 -21.9964)
		(end 24.223472 -21.75256)
		(width 0.1397)
		(layer "B.Cu")
		(net "P2E_CPU_SAS_TX_DP7")
	)
	(segment
		(start 24.28748 -14.459712)
		(end 24.854916 -14.459712)
		(width 0.1397)
		(layer "B.Cu")
		(net "P2E_CPU_SAS_TX_DP7")
	)
	(segment
		(start 24.854916 -14.459712)
		(end 25.195276 -14.119352)
		(width 0.1397)
		(layer "B.Cu")
		(net "P2E_CPU_SAS_TX_DP7")
	)
	(segment
		(start 24.671528 -9.468612)
		(end 24.671528 -6.07568)
		(width 0.1397)
		(layer "B.Cu")
		(net "P2E_CPU_SAS_TX_DP7")
	)
	(segment
		(start 25.195276 -10.512552)
		(end 25.195276 -9.948672)
		(width 0.1397)
		(layer "B.Cu")
		(net "P2E_CPU_SAS_TX_DP7")
	)
	(segment
		(start 24.811228 -9.608312)
		(end 24.671528 -9.468612)
		(width 0.1397)
		(layer "B.Cu")
		(net "P2E_CPU_SAS_TX_DP7")
	)
	(segment
		(start 24.223472 -21.75256)
		(end 24.223472 -18.15084)
		(width 0.1397)
		(layer "B.Cu")
		(net "P2E_CPU_SAS_TX_DP7")
	)
	(segment
		(start 24.14778 -12.796012)
		(end 24.28748 -12.656312)
		(width 0.1397)
		(layer "B.Cu")
		(net "P2E_CPU_SAS_TX_DP7")
	)
	(segment
		(start 25.195276 -12.315952)
		(end 25.195276 -11.752072)
		(width 0.1397)
		(layer "B.Cu")
		(net "P2E_CPU_SAS_TX_DP7")
	)
	(segment
		(start 24.14778 -13.075412)
		(end 24.14778 -12.796012)
		(width 0.1397)
		(layer "B.Cu")
		(net "P2E_CPU_SAS_TX_DP7")
	)
	(segment
		(start 24.14778 -10.992612)
		(end 24.28748 -10.852912)
		(width 0.1397)
		(layer "B.Cu")
		(net "P2E_CPU_SAS_TX_DP7")
	)
	(segment
		(start 25.175972 -15.879572)
		(end 24.14778 -14.85138)
		(width 0.1397)
		(layer "B.Cu")
		(net "P2E_CPU_SAS_TX_DP7")
	)
	(segment
		(start 25.195276 -13.555472)
		(end 24.854916 -13.215112)
		(width 0.1397)
		(layer "B.Cu")
		(net "P2E_CPU_SAS_TX_DP7")
	)
	(segment
		(start 24.997918 -21.149564)
		(end 24.997918 -21.793454)
		(width 0.1397)
		(layer "B.Cu")
		(net "P2E_CPU_SAS_TX_DP7")
	)
	(segment
		(start 28.14828 -10.254742)
		(end 28.70962 -10.254742)
		(width 0.1397)
		(layer "B.Cu")
		(net "P2E_CPU_SAS_TX_DN6")
	)
	(segment
		(start 28.70962 -12.058142)
		(end 28.84932 -11.918442)
		(width 0.1397)
		(layer "B.Cu")
		(net "P2E_CPU_SAS_TX_DN6")
	)
	(segment
		(start 28.832302 -15.786862)
		(end 27.80792 -14.76248)
		(width 0.1397)
		(layer "B.Cu")
		(net "P2E_CPU_SAS_TX_DN6")
	)
	(segment
		(start 28.832302 -17.0561)
		(end 28.832302 -15.786862)
		(width 0.1397)
		(layer "B.Cu")
		(net "P2E_CPU_SAS_TX_DN6")
	)
	(segment
		(start 28.84932 -9.835642)
		(end 28.70962 -9.695942)
		(width 0.1397)
		(layer "B.Cu")
		(net "P2E_CPU_SAS_TX_DN6")
	)
	(segment
		(start 28.66898 -9.695942)
		(end 28.32862 -9.355582)
		(width 0.1397)
		(layer "B.Cu")
		(net "P2E_CPU_SAS_TX_DN6")
	)
	(segment
		(start 28.184602 -22.96287)
		(end 28.184602 -22.1996)
		(width 0.1397)
		(layer "B.Cu")
		(net "P2E_CPU_SAS_TX_DN6")
	)
	(segment
		(start 27.80792 -14.76248)
		(end 27.80792 -14.201902)
		(width 0.1397)
		(layer "B.Cu")
		(net "P2E_CPU_SAS_TX_DN6")
	)
	(segment
		(start 28.000452 -23.149814)
		(end 27.997658 -23.149814)
		(width 0.1397)
		(layer "B.Cu")
		(net "P2E_CPU_SAS_TX_DN6")
	)
	(segment
		(start 27.80792 -10.595102)
		(end 28.14828 -10.254742)
		(width 0.1397)
		(layer "B.Cu")
		(net "P2E_CPU_SAS_TX_DN6")
	)
	(segment
		(start 28.14828 -13.861542)
		(end 28.70962 -13.861542)
		(width 0.1397)
		(layer "B.Cu")
		(net "P2E_CPU_SAS_TX_DN6")
	)
	(segment
		(start 28.14828 -13.302742)
		(end 27.80792 -12.962382)
		(width 0.1397)
		(layer "B.Cu")
		(net "P2E_CPU_SAS_TX_DN6")
	)
	(segment
		(start 28.70962 -13.861542)
		(end 28.84932 -13.721842)
		(width 0.1397)
		(layer "B.Cu")
		(net "P2E_CPU_SAS_TX_DN6")
	)
	(segment
		(start 28.84932 -13.442442)
		(end 28.70962 -13.302742)
		(width 0.1397)
		(layer "B.Cu")
		(net "P2E_CPU_SAS_TX_DN6")
	)
	(segment
		(start 28.84932 -10.115042)
		(end 28.84932 -9.835642)
		(width 0.1397)
		(layer "B.Cu")
		(net "P2E_CPU_SAS_TX_DN6")
	)
	(segment
		(start 27.80792 -14.201902)
		(end 28.14828 -13.861542)
		(width 0.1397)
		(layer "B.Cu")
		(net "P2E_CPU_SAS_TX_DN6")
	)
	(segment
		(start 28.70962 -9.695942)
		(end 28.66898 -9.695942)
		(width 0.1397)
		(layer "B.Cu")
		(net "P2E_CPU_SAS_TX_DN6")
	)
	(segment
		(start 27.879802 -18.0086)
		(end 28.832302 -17.0561)
		(width 0.1397)
		(layer "B.Cu")
		(net "P2E_CPU_SAS_TX_DN6")
	)
	(segment
		(start 27.80792 -12.398502)
		(end 28.14828 -12.058142)
		(width 0.1397)
		(layer "B.Cu")
		(net "P2E_CPU_SAS_TX_DN6")
	)
	(segment
		(start 27.997658 -23.149814)
		(end 28.184602 -22.96287)
		(width 0.1397)
		(layer "B.Cu")
		(net "P2E_CPU_SAS_TX_DN6")
	)
	(segment
		(start 27.80792 -12.962382)
		(end 27.80792 -12.398502)
		(width 0.1397)
		(layer "B.Cu")
		(net "P2E_CPU_SAS_TX_DN6")
	)
	(segment
		(start 27.80792 -11.158982)
		(end 27.80792 -10.595102)
		(width 0.1397)
		(layer "B.Cu")
		(net "P2E_CPU_SAS_TX_DN6")
	)
	(segment
		(start 28.84932 -11.639042)
		(end 28.70962 -11.499342)
		(width 0.1397)
		(layer "B.Cu")
		(net "P2E_CPU_SAS_TX_DN6")
	)
	(segment
		(start 28.184602 -22.1996)
		(end 27.879802 -21.8948)
		(width 0.1397)
		(layer "B.Cu")
		(net "P2E_CPU_SAS_TX_DN6")
	)
	(segment
		(start 28.14828 -12.058142)
		(end 28.70962 -12.058142)
		(width 0.1397)
		(layer "B.Cu")
		(net "P2E_CPU_SAS_TX_DN6")
	)
	(segment
		(start 28.14828 -11.499342)
		(end 27.80792 -11.158982)
		(width 0.1397)
		(layer "B.Cu")
		(net "P2E_CPU_SAS_TX_DN6")
	)
	(segment
		(start 28.84932 -11.918442)
		(end 28.84932 -11.639042)
		(width 0.1397)
		(layer "B.Cu")
		(net "P2E_CPU_SAS_TX_DN6")
	)
	(segment
		(start 28.32862 -6.07568)
		(end 27.999944 -5.747004)
		(width 0.1397)
		(layer "B.Cu")
		(net "P2E_CPU_SAS_TX_DN6")
	)
	(segment
		(start 28.70962 -11.499342)
		(end 28.14828 -11.499342)
		(width 0.1397)
		(layer "B.Cu")
		(net "P2E_CPU_SAS_TX_DN6")
	)
	(segment
		(start 28.32862 -9.355582)
		(end 28.32862 -6.07568)
		(width 0.1397)
		(layer "B.Cu")
		(net "P2E_CPU_SAS_TX_DN6")
	)
	(segment
		(start 27.999944 -5.747004)
		(end 27.999944 -3.114548)
		(width 0.1397)
		(layer "B.Cu")
		(net "P2E_CPU_SAS_TX_DN6")
	)
	(segment
		(start 28.70962 -13.302742)
		(end 28.14828 -13.302742)
		(width 0.1397)
		(layer "B.Cu")
		(net "P2E_CPU_SAS_TX_DN6")
	)
	(segment
		(start 28.70962 -10.254742)
		(end 28.84932 -10.115042)
		(width 0.1397)
		(layer "B.Cu")
		(net "P2E_CPU_SAS_TX_DN6")
	)
	(segment
		(start 27.879802 -21.8948)
		(end 27.879802 -18.0086)
		(width 0.1397)
		(layer "B.Cu")
		(net "P2E_CPU_SAS_TX_DN6")
	)
	(segment
		(start 28.84932 -13.721842)
		(end 28.84932 -13.442442)
		(width 0.1397)
		(layer "B.Cu")
		(net "P2E_CPU_SAS_TX_DN6")
	)
	(segment
		(start 28.29052 -12.401042)
		(end 28.85186 -12.401042)
		(width 0.1397)
		(layer "B.Cu")
		(net "P2E_CPU_SAS_TX_DP6")
	)
	(segment
		(start 29.19222 -9.693402)
		(end 28.85186 -9.353042)
		(width 0.1397)
		(layer "B.Cu")
		(net "P2E_CPU_SAS_TX_DP6")
	)
	(segment
		(start 28.222702 -18.15084)
		(end 29.175202 -17.19834)
		(width 0.1397)
		(layer "B.Cu")
		(net "P2E_CPU_SAS_TX_DP6")
	)
	(segment
		(start 29.19222 -13.300202)
		(end 28.85186 -12.959842)
		(width 0.1397)
		(layer "B.Cu")
		(net "P2E_CPU_SAS_TX_DP6")
	)
	(segment
		(start 28.85186 -9.353042)
		(end 28.81122 -9.353042)
		(width 0.1397)
		(layer "B.Cu")
		(net "P2E_CPU_SAS_TX_DP6")
	)
	(segment
		(start 28.85186 -12.959842)
		(end 28.29052 -12.959842)
		(width 0.1397)
		(layer "B.Cu")
		(net "P2E_CPU_SAS_TX_DP6")
	)
	(segment
		(start 28.29052 -11.156442)
		(end 28.15082 -11.016742)
		(width 0.1397)
		(layer "B.Cu")
		(net "P2E_CPU_SAS_TX_DP6")
	)
	(segment
		(start 28.85186 -10.597642)
		(end 29.19222 -10.257282)
		(width 0.1397)
		(layer "B.Cu")
		(net "P2E_CPU_SAS_TX_DP6")
	)
	(segment
		(start 28.85186 -14.204442)
		(end 29.19222 -13.864082)
		(width 0.1397)
		(layer "B.Cu")
		(net "P2E_CPU_SAS_TX_DP6")
	)
	(segment
		(start 29.19222 -10.257282)
		(end 29.19222 -9.693402)
		(width 0.1397)
		(layer "B.Cu")
		(net "P2E_CPU_SAS_TX_DP6")
	)
	(segment
		(start 29.175202 -15.644622)
		(end 28.15082 -14.62024)
		(width 0.1397)
		(layer "B.Cu")
		(net "P2E_CPU_SAS_TX_DP6")
	)
	(segment
		(start 28.85186 -11.156442)
		(end 28.29052 -11.156442)
		(width 0.1397)
		(layer "B.Cu")
		(net "P2E_CPU_SAS_TX_DP6")
	)
	(segment
		(start 29.19222 -11.496802)
		(end 28.85186 -11.156442)
		(width 0.1397)
		(layer "B.Cu")
		(net "P2E_CPU_SAS_TX_DP6")
	)
	(segment
		(start 28.997148 -21.149564)
		(end 28.997148 -21.793454)
		(width 0.1397)
		(layer "B.Cu")
		(net "P2E_CPU_SAS_TX_DP6")
	)
	(segment
		(start 28.466542 -21.9964)
		(end 28.222702 -21.75256)
		(width 0.1397)
		(layer "B.Cu")
		(net "P2E_CPU_SAS_TX_DP6")
	)
	(segment
		(start 28.15082 -10.737342)
		(end 28.29052 -10.597642)
		(width 0.1397)
		(layer "B.Cu")
		(net "P2E_CPU_SAS_TX_DP6")
	)
	(segment
		(start 28.29052 -10.597642)
		(end 28.85186 -10.597642)
		(width 0.1397)
		(layer "B.Cu")
		(net "P2E_CPU_SAS_TX_DP6")
	)
	(segment
		(start 28.999942 -21.149564)
		(end 28.997148 -21.149564)
		(width 0.1397)
		(layer "B.Cu")
		(net "P2E_CPU_SAS_TX_DP6")
	)
	(segment
		(start 28.997148 -21.793454)
		(end 28.794202 -21.9964)
		(width 0.1397)
		(layer "B.Cu")
		(net "P2E_CPU_SAS_TX_DP6")
	)
	(segment
		(start 28.222702 -21.75256)
		(end 28.222702 -18.15084)
		(width 0.1397)
		(layer "B.Cu")
		(net "P2E_CPU_SAS_TX_DP6")
	)
	(segment
		(start 28.29052 -12.959842)
		(end 28.15082 -12.820142)
		(width 0.1397)
		(layer "B.Cu")
		(net "P2E_CPU_SAS_TX_DP6")
	)
	(segment
		(start 28.15082 -14.62024)
		(end 28.15082 -14.344142)
		(width 0.1397)
		(layer "B.Cu")
		(net "P2E_CPU_SAS_TX_DP6")
	)
	(segment
		(start 28.794202 -21.9964)
		(end 28.466542 -21.9964)
		(width 0.1397)
		(layer "B.Cu")
		(net "P2E_CPU_SAS_TX_DP6")
	)
	(segment
		(start 29.19222 -12.060682)
		(end 29.19222 -11.496802)
		(width 0.1397)
		(layer "B.Cu")
		(net "P2E_CPU_SAS_TX_DP6")
	)
	(segment
		(start 28.15082 -12.820142)
		(end 28.15082 -12.540742)
		(width 0.1397)
		(layer "B.Cu")
		(net "P2E_CPU_SAS_TX_DP6")
	)
	(segment
		(start 28.67152 -9.213342)
		(end 28.67152 -6.07568)
		(width 0.1397)
		(layer "B.Cu")
		(net "P2E_CPU_SAS_TX_DP6")
	)
	(segment
		(start 28.67152 -6.07568)
		(end 28.999942 -5.747258)
		(width 0.1397)
		(layer "B.Cu")
		(net "P2E_CPU_SAS_TX_DP6")
	)
	(segment
		(start 28.15082 -11.016742)
		(end 28.15082 -10.737342)
		(width 0.1397)
		(layer "B.Cu")
		(net "P2E_CPU_SAS_TX_DP6")
	)
	(segment
		(start 29.19222 -13.864082)
		(end 29.19222 -13.300202)
		(width 0.1397)
		(layer "B.Cu")
		(net "P2E_CPU_SAS_TX_DP6")
	)
	(segment
		(start 28.999942 -5.747258)
		(end 28.999942 -3.114548)
		(width 0.1397)
		(layer "B.Cu")
		(net "P2E_CPU_SAS_TX_DP6")
	)
	(segment
		(start 28.29052 -14.204442)
		(end 28.85186 -14.204442)
		(width 0.1397)
		(layer "B.Cu")
		(net "P2E_CPU_SAS_TX_DP6")
	)
	(segment
		(start 28.15082 -12.540742)
		(end 28.29052 -12.401042)
		(width 0.1397)
		(layer "B.Cu")
		(net "P2E_CPU_SAS_TX_DP6")
	)
	(segment
		(start 29.175202 -17.19834)
		(end 29.175202 -15.644622)
		(width 0.1397)
		(layer "B.Cu")
		(net "P2E_CPU_SAS_TX_DP6")
	)
	(segment
		(start 28.85186 -12.401042)
		(end 29.19222 -12.060682)
		(width 0.1397)
		(layer "B.Cu")
		(net "P2E_CPU_SAS_TX_DP6")
	)
	(segment
		(start 28.15082 -14.344142)
		(end 28.29052 -14.204442)
		(width 0.1397)
		(layer "B.Cu")
		(net "P2E_CPU_SAS_TX_DP6")
	)
	(segment
		(start 28.81122 -9.353042)
		(end 28.67152 -9.213342)
		(width 0.1397)
		(layer "B.Cu")
		(net "P2E_CPU_SAS_TX_DP6")
	)
	(segment
		(start 32.861504 -11.835892)
		(end 32.721804 -11.696192)
		(width 0.1397)
		(layer "B.Cu")
		(net "P2E_CPU_SAS_TX_DN5")
	)
	(segment
		(start 32.13608 -11.696192)
		(end 31.79572 -11.355832)
		(width 0.1397)
		(layer "B.Cu")
		(net "P2E_CPU_SAS_TX_DN5")
	)
	(segment
		(start 32.861504 -13.639292)
		(end 32.721804 -13.499592)
		(width 0.1397)
		(layer "B.Cu")
		(net "P2E_CPU_SAS_TX_DN5")
	)
	(segment
		(start 31.79572 -13.159232)
		(end 31.79572 -12.595352)
		(width 0.1397)
		(layer "B.Cu")
		(net "P2E_CPU_SAS_TX_DN5")
	)
	(segment
		(start 32.721804 -12.254992)
		(end 32.861504 -12.115292)
		(width 0.1397)
		(layer "B.Cu")
		(net "P2E_CPU_SAS_TX_DN5")
	)
	(segment
		(start 31.79572 -14.92758)
		(end 31.79572 -14.398752)
		(width 0.1397)
		(layer "B.Cu")
		(net "P2E_CPU_SAS_TX_DN5")
	)
	(segment
		(start 32.861504 -10.032492)
		(end 32.721804 -9.892792)
		(width 0.1397)
		(layer "B.Cu")
		(net "P2E_CPU_SAS_TX_DN5")
	)
	(segment
		(start 32.721804 -9.892792)
		(end 32.668972 -9.892792)
		(width 0.1397)
		(layer "B.Cu")
		(net "P2E_CPU_SAS_TX_DN5")
	)
	(segment
		(start 32.831532 -15.963392)
		(end 31.79572 -14.92758)
		(width 0.1397)
		(layer "B.Cu")
		(net "P2E_CPU_SAS_TX_DN5")
	)
	(segment
		(start 31.996888 -23.149814)
		(end 32.183832 -22.96287)
		(width 0.1397)
		(layer "B.Cu")
		(net "P2E_CPU_SAS_TX_DN5")
	)
	(segment
		(start 31.79572 -12.595352)
		(end 32.13608 -12.254992)
		(width 0.1397)
		(layer "B.Cu")
		(net "P2E_CPU_SAS_TX_DN5")
	)
	(segment
		(start 32.328612 -6.07568)
		(end 31.999936 -5.747004)
		(width 0.1397)
		(layer "B.Cu")
		(net "P2E_CPU_SAS_TX_DN5")
	)
	(segment
		(start 32.861504 -12.115292)
		(end 32.861504 -11.835892)
		(width 0.1397)
		(layer "B.Cu")
		(net "P2E_CPU_SAS_TX_DN5")
	)
	(segment
		(start 31.999936 -5.747004)
		(end 31.999936 -3.114548)
		(width 0.1397)
		(layer "B.Cu")
		(net "P2E_CPU_SAS_TX_DN5")
	)
	(segment
		(start 32.721804 -13.499592)
		(end 32.13608 -13.499592)
		(width 0.1397)
		(layer "B.Cu")
		(net "P2E_CPU_SAS_TX_DN5")
	)
	(segment
		(start 32.721804 -10.451592)
		(end 32.861504 -10.311892)
		(width 0.1397)
		(layer "B.Cu")
		(net "P2E_CPU_SAS_TX_DN5")
	)
	(segment
		(start 32.831532 -17.0561)
		(end 32.831532 -15.963392)
		(width 0.1397)
		(layer "B.Cu")
		(net "P2E_CPU_SAS_TX_DN5")
	)
	(segment
		(start 32.13608 -12.254992)
		(end 32.721804 -12.254992)
		(width 0.1397)
		(layer "B.Cu")
		(net "P2E_CPU_SAS_TX_DN5")
	)
	(segment
		(start 31.79572 -11.355832)
		(end 31.79572 -10.791952)
		(width 0.1397)
		(layer "B.Cu")
		(net "P2E_CPU_SAS_TX_DN5")
	)
	(segment
		(start 32.13608 -13.499592)
		(end 31.79572 -13.159232)
		(width 0.1397)
		(layer "B.Cu")
		(net "P2E_CPU_SAS_TX_DN5")
	)
	(segment
		(start 32.183832 -22.1996)
		(end 31.879032 -21.8948)
		(width 0.1397)
		(layer "B.Cu")
		(net "P2E_CPU_SAS_TX_DN5")
	)
	(segment
		(start 32.13608 -10.451592)
		(end 32.721804 -10.451592)
		(width 0.1397)
		(layer "B.Cu")
		(net "P2E_CPU_SAS_TX_DN5")
	)
	(segment
		(start 32.183832 -22.96287)
		(end 32.183832 -22.1996)
		(width 0.1397)
		(layer "B.Cu")
		(net "P2E_CPU_SAS_TX_DN5")
	)
	(segment
		(start 32.861504 -13.918692)
		(end 32.861504 -13.639292)
		(width 0.1397)
		(layer "B.Cu")
		(net "P2E_CPU_SAS_TX_DN5")
	)
	(segment
		(start 32.13608 -14.058392)
		(end 32.721804 -14.058392)
		(width 0.1397)
		(layer "B.Cu")
		(net "P2E_CPU_SAS_TX_DN5")
	)
	(segment
		(start 32.668972 -9.892792)
		(end 32.328612 -9.552432)
		(width 0.1397)
		(layer "B.Cu")
		(net "P2E_CPU_SAS_TX_DN5")
	)
	(segment
		(start 31.879032 -18.0086)
		(end 32.831532 -17.0561)
		(width 0.1397)
		(layer "B.Cu")
		(net "P2E_CPU_SAS_TX_DN5")
	)
	(segment
		(start 32.328612 -9.552432)
		(end 32.328612 -6.07568)
		(width 0.1397)
		(layer "B.Cu")
		(net "P2E_CPU_SAS_TX_DN5")
	)
	(segment
		(start 32.721804 -11.696192)
		(end 32.13608 -11.696192)
		(width 0.1397)
		(layer "B.Cu")
		(net "P2E_CPU_SAS_TX_DN5")
	)
	(segment
		(start 31.999682 -23.149814)
		(end 31.996888 -23.149814)
		(width 0.1397)
		(layer "B.Cu")
		(net "P2E_CPU_SAS_TX_DN5")
	)
	(segment
		(start 31.79572 -14.398752)
		(end 32.13608 -14.058392)
		(width 0.1397)
		(layer "B.Cu")
		(net "P2E_CPU_SAS_TX_DN5")
	)
	(segment
		(start 32.721804 -14.058392)
		(end 32.861504 -13.918692)
		(width 0.1397)
		(layer "B.Cu")
		(net "P2E_CPU_SAS_TX_DN5")
	)
	(segment
		(start 31.879032 -21.8948)
		(end 31.879032 -18.0086)
		(width 0.1397)
		(layer "B.Cu")
		(net "P2E_CPU_SAS_TX_DN5")
	)
	(segment
		(start 31.79572 -10.791952)
		(end 32.13608 -10.451592)
		(width 0.1397)
		(layer "B.Cu")
		(net "P2E_CPU_SAS_TX_DN5")
	)
	(segment
		(start 32.861504 -10.311892)
		(end 32.861504 -10.032492)
		(width 0.1397)
		(layer "B.Cu")
		(net "P2E_CPU_SAS_TX_DN5")
	)
	(segment
		(start 33.000442 -21.149564)
		(end 32.996378 -21.149564)
		(width 0.1397)
		(layer "B.Cu")
		(net "P2E_CPU_SAS_TX_DP5")
	)
	(segment
		(start 33.204404 -13.497052)
		(end 32.864044 -13.156692)
		(width 0.1397)
		(layer "B.Cu")
		(net "P2E_CPU_SAS_TX_DP5")
	)
	(segment
		(start 32.671512 -6.07568)
		(end 32.999934 -5.747258)
		(width 0.1397)
		(layer "B.Cu")
		(net "P2E_CPU_SAS_TX_DP5")
	)
	(segment
		(start 32.793432 -21.9964)
		(end 32.465772 -21.9964)
		(width 0.1397)
		(layer "B.Cu")
		(net "P2E_CPU_SAS_TX_DP5")
	)
	(segment
		(start 32.811212 -9.549892)
		(end 32.671512 -9.410192)
		(width 0.1397)
		(layer "B.Cu")
		(net "P2E_CPU_SAS_TX_DP5")
	)
	(segment
		(start 33.174432 -17.19834)
		(end 33.174432 -15.821152)
		(width 0.1397)
		(layer "B.Cu")
		(net "P2E_CPU_SAS_TX_DP5")
	)
	(segment
		(start 32.13862 -14.540992)
		(end 32.27832 -14.401292)
		(width 0.1397)
		(layer "B.Cu")
		(net "P2E_CPU_SAS_TX_DP5")
	)
	(segment
		(start 32.13862 -13.016992)
		(end 32.13862 -12.737592)
		(width 0.1397)
		(layer "B.Cu")
		(net "P2E_CPU_SAS_TX_DP5")
	)
	(segment
		(start 33.174432 -15.821152)
		(end 32.13862 -14.78534)
		(width 0.1397)
		(layer "B.Cu")
		(net "P2E_CPU_SAS_TX_DP5")
	)
	(segment
		(start 33.204404 -12.257532)
		(end 33.204404 -11.693652)
		(width 0.1397)
		(layer "B.Cu")
		(net "P2E_CPU_SAS_TX_DP5")
	)
	(segment
		(start 32.27832 -13.156692)
		(end 32.13862 -13.016992)
		(width 0.1397)
		(layer "B.Cu")
		(net "P2E_CPU_SAS_TX_DP5")
	)
	(segment
		(start 33.204404 -9.890252)
		(end 32.864044 -9.549892)
		(width 0.1397)
		(layer "B.Cu")
		(net "P2E_CPU_SAS_TX_DP5")
	)
	(segment
		(start 32.465772 -21.9964)
		(end 32.221932 -21.75256)
		(width 0.1397)
		(layer "B.Cu")
		(net "P2E_CPU_SAS_TX_DP5")
	)
	(segment
		(start 33.204404 -11.693652)
		(end 32.864044 -11.353292)
		(width 0.1397)
		(layer "B.Cu")
		(net "P2E_CPU_SAS_TX_DP5")
	)
	(segment
		(start 32.13862 -12.737592)
		(end 32.27832 -12.597892)
		(width 0.1397)
		(layer "B.Cu")
		(net "P2E_CPU_SAS_TX_DP5")
	)
	(segment
		(start 32.13862 -11.213592)
		(end 32.13862 -10.934192)
		(width 0.1397)
		(layer "B.Cu")
		(net "P2E_CPU_SAS_TX_DP5")
	)
	(segment
		(start 32.864044 -14.401292)
		(end 33.204404 -14.060932)
		(width 0.1397)
		(layer "B.Cu")
		(net "P2E_CPU_SAS_TX_DP5")
	)
	(segment
		(start 32.13862 -10.934192)
		(end 32.27832 -10.794492)
		(width 0.1397)
		(layer "B.Cu")
		(net "P2E_CPU_SAS_TX_DP5")
	)
	(segment
		(start 32.671512 -9.410192)
		(end 32.671512 -6.07568)
		(width 0.1397)
		(layer "B.Cu")
		(net "P2E_CPU_SAS_TX_DP5")
	)
	(segment
		(start 32.996378 -21.149564)
		(end 32.996378 -21.793454)
		(width 0.1397)
		(layer "B.Cu")
		(net "P2E_CPU_SAS_TX_DP5")
	)
	(segment
		(start 33.204404 -14.060932)
		(end 33.204404 -13.497052)
		(width 0.1397)
		(layer "B.Cu")
		(net "P2E_CPU_SAS_TX_DP5")
	)
	(segment
		(start 32.27832 -10.794492)
		(end 32.864044 -10.794492)
		(width 0.1397)
		(layer "B.Cu")
		(net "P2E_CPU_SAS_TX_DP5")
	)
	(segment
		(start 32.27832 -11.353292)
		(end 32.13862 -11.213592)
		(width 0.1397)
		(layer "B.Cu")
		(net "P2E_CPU_SAS_TX_DP5")
	)
	(segment
		(start 32.864044 -9.549892)
		(end 32.811212 -9.549892)
		(width 0.1397)
		(layer "B.Cu")
		(net "P2E_CPU_SAS_TX_DP5")
	)
	(segment
		(start 32.27832 -14.401292)
		(end 32.864044 -14.401292)
		(width 0.1397)
		(layer "B.Cu")
		(net "P2E_CPU_SAS_TX_DP5")
	)
	(segment
		(start 32.864044 -11.353292)
		(end 32.27832 -11.353292)
		(width 0.1397)
		(layer "B.Cu")
		(net "P2E_CPU_SAS_TX_DP5")
	)
	(segment
		(start 33.204404 -10.454132)
		(end 33.204404 -9.890252)
		(width 0.1397)
		(layer "B.Cu")
		(net "P2E_CPU_SAS_TX_DP5")
	)
	(segment
		(start 32.221932 -21.75256)
		(end 32.221932 -18.15084)
		(width 0.1397)
		(layer "B.Cu")
		(net "P2E_CPU_SAS_TX_DP5")
	)
	(segment
		(start 32.221932 -18.15084)
		(end 33.174432 -17.19834)
		(width 0.1397)
		(layer "B.Cu")
		(net "P2E_CPU_SAS_TX_DP5")
	)
	(segment
		(start 32.996378 -21.793454)
		(end 32.793432 -21.9964)
		(width 0.1397)
		(layer "B.Cu")
		(net "P2E_CPU_SAS_TX_DP5")
	)
	(segment
		(start 32.999934 -5.747258)
		(end 32.999934 -3.114548)
		(width 0.1397)
		(layer "B.Cu")
		(net "P2E_CPU_SAS_TX_DP5")
	)
	(segment
		(start 32.864044 -12.597892)
		(end 33.204404 -12.257532)
		(width 0.1397)
		(layer "B.Cu")
		(net "P2E_CPU_SAS_TX_DP5")
	)
	(segment
		(start 32.13862 -14.78534)
		(end 32.13862 -14.540992)
		(width 0.1397)
		(layer "B.Cu")
		(net "P2E_CPU_SAS_TX_DP5")
	)
	(segment
		(start 32.864044 -10.794492)
		(end 33.204404 -10.454132)
		(width 0.1397)
		(layer "B.Cu")
		(net "P2E_CPU_SAS_TX_DP5")
	)
	(segment
		(start 32.864044 -13.156692)
		(end 32.27832 -13.156692)
		(width 0.1397)
		(layer "B.Cu")
		(net "P2E_CPU_SAS_TX_DP5")
	)
	(segment
		(start 32.27832 -12.597892)
		(end 32.864044 -12.597892)
		(width 0.1397)
		(layer "B.Cu")
		(net "P2E_CPU_SAS_TX_DP5")
	)
	(segment
		(start 36.718748 -13.462762)
		(end 36.13912 -13.462762)
		(width 0.1397)
		(layer "B.Cu")
		(net "P2E_CPU_SAS_TX_DN4")
	)
	(segment
		(start 35.79876 -12.558522)
		(end 36.13912 -12.218162)
		(width 0.1397)
		(layer "B.Cu")
		(net "P2E_CPU_SAS_TX_DN4")
	)
	(segment
		(start 36.13912 -14.021562)
		(end 36.718748 -14.021562)
		(width 0.1397)
		(layer "B.Cu")
		(net "P2E_CPU_SAS_TX_DN4")
	)
	(segment
		(start 35.878262 -18.0086)
		(end 36.830762 -17.0561)
		(width 0.1397)
		(layer "B.Cu")
		(net "P2E_CPU_SAS_TX_DN4")
	)
	(segment
		(start 36.858448 -9.995662)
		(end 36.718748 -9.855962)
		(width 0.1397)
		(layer "B.Cu")
		(net "P2E_CPU_SAS_TX_DN4")
	)
	(segment
		(start 36.858448 -12.078462)
		(end 36.858448 -11.799062)
		(width 0.1397)
		(layer "B.Cu")
		(net "P2E_CPU_SAS_TX_DN4")
	)
	(segment
		(start 36.328604 -6.07568)
		(end 35.999928 -5.747004)
		(width 0.1397)
		(layer "B.Cu")
		(net "P2E_CPU_SAS_TX_DN4")
	)
	(segment
		(start 36.718748 -10.414762)
		(end 36.858448 -10.275062)
		(width 0.1397)
		(layer "B.Cu")
		(net "P2E_CPU_SAS_TX_DN4")
	)
	(segment
		(start 36.718748 -9.855962)
		(end 36.668964 -9.855962)
		(width 0.1397)
		(layer "B.Cu")
		(net "P2E_CPU_SAS_TX_DN4")
	)
	(segment
		(start 36.13912 -11.659362)
		(end 35.79876 -11.319002)
		(width 0.1397)
		(layer "B.Cu")
		(net "P2E_CPU_SAS_TX_DN4")
	)
	(segment
		(start 36.000182 -23.149814)
		(end 36.183062 -22.966934)
		(width 0.1397)
		(layer "B.Cu")
		(net "P2E_CPU_SAS_TX_DN4")
	)
	(segment
		(start 36.858448 -10.275062)
		(end 36.858448 -9.995662)
		(width 0.1397)
		(layer "B.Cu")
		(net "P2E_CPU_SAS_TX_DN4")
	)
	(segment
		(start 36.718748 -11.659362)
		(end 36.13912 -11.659362)
		(width 0.1397)
		(layer "B.Cu")
		(net "P2E_CPU_SAS_TX_DN4")
	)
	(segment
		(start 36.858448 -13.602462)
		(end 36.718748 -13.462762)
		(width 0.1397)
		(layer "B.Cu")
		(net "P2E_CPU_SAS_TX_DN4")
	)
	(segment
		(start 36.13912 -13.462762)
		(end 35.79876 -13.122402)
		(width 0.1397)
		(layer "B.Cu")
		(net "P2E_CPU_SAS_TX_DN4")
	)
	(segment
		(start 36.858448 -13.881862)
		(end 36.858448 -13.602462)
		(width 0.1397)
		(layer "B.Cu")
		(net "P2E_CPU_SAS_TX_DN4")
	)
	(segment
		(start 36.183062 -22.1996)
		(end 35.878262 -21.8948)
		(width 0.1397)
		(layer "B.Cu")
		(net "P2E_CPU_SAS_TX_DN4")
	)
	(segment
		(start 35.79876 -13.122402)
		(end 35.79876 -12.558522)
		(width 0.1397)
		(layer "B.Cu")
		(net "P2E_CPU_SAS_TX_DN4")
	)
	(segment
		(start 35.79876 -10.755122)
		(end 36.13912 -10.414762)
		(width 0.1397)
		(layer "B.Cu")
		(net "P2E_CPU_SAS_TX_DN4")
	)
	(segment
		(start 36.13912 -12.218162)
		(end 36.718748 -12.218162)
		(width 0.1397)
		(layer "B.Cu")
		(net "P2E_CPU_SAS_TX_DN4")
	)
	(segment
		(start 36.668964 -9.855962)
		(end 36.328604 -9.515602)
		(width 0.1397)
		(layer "B.Cu")
		(net "P2E_CPU_SAS_TX_DN4")
	)
	(segment
		(start 35.79876 -11.319002)
		(end 35.79876 -10.755122)
		(width 0.1397)
		(layer "B.Cu")
		(net "P2E_CPU_SAS_TX_DN4")
	)
	(segment
		(start 36.858448 -11.799062)
		(end 36.718748 -11.659362)
		(width 0.1397)
		(layer "B.Cu")
		(net "P2E_CPU_SAS_TX_DN4")
	)
	(segment
		(start 36.830762 -17.0561)
		(end 36.830762 -15.926562)
		(width 0.1397)
		(layer "B.Cu")
		(net "P2E_CPU_SAS_TX_DN4")
	)
	(segment
		(start 35.79876 -14.361922)
		(end 36.13912 -14.021562)
		(width 0.1397)
		(layer "B.Cu")
		(net "P2E_CPU_SAS_TX_DN4")
	)
	(segment
		(start 36.830762 -15.926562)
		(end 35.79876 -14.89456)
		(width 0.1397)
		(layer "B.Cu")
		(net "P2E_CPU_SAS_TX_DN4")
	)
	(segment
		(start 35.999928 -5.747004)
		(end 35.999928 -3.114548)
		(width 0.1397)
		(layer "B.Cu")
		(net "P2E_CPU_SAS_TX_DN4")
	)
	(segment
		(start 36.718748 -14.021562)
		(end 36.858448 -13.881862)
		(width 0.1397)
		(layer "B.Cu")
		(net "P2E_CPU_SAS_TX_DN4")
	)
	(segment
		(start 36.328604 -9.515602)
		(end 36.328604 -6.07568)
		(width 0.1397)
		(layer "B.Cu")
		(net "P2E_CPU_SAS_TX_DN4")
	)
	(segment
		(start 36.183062 -22.966934)
		(end 36.183062 -22.1996)
		(width 0.1397)
		(layer "B.Cu")
		(net "P2E_CPU_SAS_TX_DN4")
	)
	(segment
		(start 36.718748 -12.218162)
		(end 36.858448 -12.078462)
		(width 0.1397)
		(layer "B.Cu")
		(net "P2E_CPU_SAS_TX_DN4")
	)
	(segment
		(start 35.878262 -21.8948)
		(end 35.878262 -18.0086)
		(width 0.1397)
		(layer "B.Cu")
		(net "P2E_CPU_SAS_TX_DN4")
	)
	(segment
		(start 36.13912 -10.414762)
		(end 36.718748 -10.414762)
		(width 0.1397)
		(layer "B.Cu")
		(net "P2E_CPU_SAS_TX_DN4")
	)
	(segment
		(start 35.79876 -14.89456)
		(end 35.79876 -14.361922)
		(width 0.1397)
		(layer "B.Cu")
		(net "P2E_CPU_SAS_TX_DN4")
	)
	(segment
		(start 36.860988 -10.757662)
		(end 37.201348 -10.417302)
		(width 0.1397)
		(layer "B.Cu")
		(net "P2E_CPU_SAS_TX_DP4")
	)
	(segment
		(start 36.860988 -14.364462)
		(end 37.201348 -14.024102)
		(width 0.1397)
		(layer "B.Cu")
		(net "P2E_CPU_SAS_TX_DP4")
	)
	(segment
		(start 36.28136 -10.757662)
		(end 36.860988 -10.757662)
		(width 0.1397)
		(layer "B.Cu")
		(net "P2E_CPU_SAS_TX_DP4")
	)
	(segment
		(start 36.14166 -14.504162)
		(end 36.28136 -14.364462)
		(width 0.1397)
		(layer "B.Cu")
		(net "P2E_CPU_SAS_TX_DP4")
	)
	(segment
		(start 37.173662 -15.784322)
		(end 36.14166 -14.75232)
		(width 0.1397)
		(layer "B.Cu")
		(net "P2E_CPU_SAS_TX_DP4")
	)
	(segment
		(start 36.221162 -21.75256)
		(end 36.221162 -18.15084)
		(width 0.1397)
		(layer "B.Cu")
		(net "P2E_CPU_SAS_TX_DP4")
	)
	(segment
		(start 36.14166 -14.75232)
		(end 36.14166 -14.504162)
		(width 0.1397)
		(layer "B.Cu")
		(net "P2E_CPU_SAS_TX_DP4")
	)
	(segment
		(start 36.792662 -21.9964)
		(end 36.465002 -21.9964)
		(width 0.1397)
		(layer "B.Cu")
		(net "P2E_CPU_SAS_TX_DP4")
	)
	(segment
		(start 36.28136 -12.561062)
		(end 36.860988 -12.561062)
		(width 0.1397)
		(layer "B.Cu")
		(net "P2E_CPU_SAS_TX_DP4")
	)
	(segment
		(start 37.201348 -12.220702)
		(end 37.201348 -11.656822)
		(width 0.1397)
		(layer "B.Cu")
		(net "P2E_CPU_SAS_TX_DP4")
	)
	(segment
		(start 36.811204 -9.513062)
		(end 36.671504 -9.373362)
		(width 0.1397)
		(layer "B.Cu")
		(net "P2E_CPU_SAS_TX_DP4")
	)
	(segment
		(start 37.173662 -17.19834)
		(end 37.173662 -15.784322)
		(width 0.1397)
		(layer "B.Cu")
		(net "P2E_CPU_SAS_TX_DP4")
	)
	(segment
		(start 36.28136 -14.364462)
		(end 36.860988 -14.364462)
		(width 0.1397)
		(layer "B.Cu")
		(net "P2E_CPU_SAS_TX_DP4")
	)
	(segment
		(start 37.201348 -11.656822)
		(end 36.860988 -11.316462)
		(width 0.1397)
		(layer "B.Cu")
		(net "P2E_CPU_SAS_TX_DP4")
	)
	(segment
		(start 36.465002 -21.9964)
		(end 36.221162 -21.75256)
		(width 0.1397)
		(layer "B.Cu")
		(net "P2E_CPU_SAS_TX_DP4")
	)
	(segment
		(start 36.995608 -21.793454)
		(end 36.792662 -21.9964)
		(width 0.1397)
		(layer "B.Cu")
		(net "P2E_CPU_SAS_TX_DP4")
	)
	(segment
		(start 36.860988 -13.119862)
		(end 36.28136 -13.119862)
		(width 0.1397)
		(layer "B.Cu")
		(net "P2E_CPU_SAS_TX_DP4")
	)
	(segment
		(start 37.201348 -10.417302)
		(end 37.201348 -9.853422)
		(width 0.1397)
		(layer "B.Cu")
		(net "P2E_CPU_SAS_TX_DP4")
	)
	(segment
		(start 36.999926 -5.747258)
		(end 36.999926 -3.114548)
		(width 0.1397)
		(layer "B.Cu")
		(net "P2E_CPU_SAS_TX_DP4")
	)
	(segment
		(start 36.995608 -21.149564)
		(end 36.995608 -21.793454)
		(width 0.1397)
		(layer "B.Cu")
		(net "P2E_CPU_SAS_TX_DP4")
	)
	(segment
		(start 37.201348 -13.460222)
		(end 36.860988 -13.119862)
		(width 0.1397)
		(layer "B.Cu")
		(net "P2E_CPU_SAS_TX_DP4")
	)
	(segment
		(start 37.201348 -14.024102)
		(end 37.201348 -13.460222)
		(width 0.1397)
		(layer "B.Cu")
		(net "P2E_CPU_SAS_TX_DP4")
	)
	(segment
		(start 36.860988 -11.316462)
		(end 36.28136 -11.316462)
		(width 0.1397)
		(layer "B.Cu")
		(net "P2E_CPU_SAS_TX_DP4")
	)
	(segment
		(start 36.14166 -12.980162)
		(end 36.14166 -12.700762)
		(width 0.1397)
		(layer "B.Cu")
		(net "P2E_CPU_SAS_TX_DP4")
	)
	(segment
		(start 37.201348 -9.853422)
		(end 36.860988 -9.513062)
		(width 0.1397)
		(layer "B.Cu")
		(net "P2E_CPU_SAS_TX_DP4")
	)
	(segment
		(start 36.14166 -12.700762)
		(end 36.28136 -12.561062)
		(width 0.1397)
		(layer "B.Cu")
		(net "P2E_CPU_SAS_TX_DP4")
	)
	(segment
		(start 36.28136 -13.119862)
		(end 36.14166 -12.980162)
		(width 0.1397)
		(layer "B.Cu")
		(net "P2E_CPU_SAS_TX_DP4")
	)
	(segment
		(start 36.860988 -9.513062)
		(end 36.811204 -9.513062)
		(width 0.1397)
		(layer "B.Cu")
		(net "P2E_CPU_SAS_TX_DP4")
	)
	(segment
		(start 36.28136 -11.316462)
		(end 36.14166 -11.176762)
		(width 0.1397)
		(layer "B.Cu")
		(net "P2E_CPU_SAS_TX_DP4")
	)
	(segment
		(start 36.860988 -12.561062)
		(end 37.201348 -12.220702)
		(width 0.1397)
		(layer "B.Cu")
		(net "P2E_CPU_SAS_TX_DP4")
	)
	(segment
		(start 36.671504 -6.07568)
		(end 36.999926 -5.747258)
		(width 0.1397)
		(layer "B.Cu")
		(net "P2E_CPU_SAS_TX_DP4")
	)
	(segment
		(start 36.671504 -9.373362)
		(end 36.671504 -6.07568)
		(width 0.1397)
		(layer "B.Cu")
		(net "P2E_CPU_SAS_TX_DP4")
	)
	(segment
		(start 36.999672 -21.149564)
		(end 36.995608 -21.149564)
		(width 0.1397)
		(layer "B.Cu")
		(net "P2E_CPU_SAS_TX_DP4")
	)
	(segment
		(start 36.14166 -11.176762)
		(end 36.14166 -10.897362)
		(width 0.1397)
		(layer "B.Cu")
		(net "P2E_CPU_SAS_TX_DP4")
	)
	(segment
		(start 36.221162 -18.15084)
		(end 37.173662 -17.19834)
		(width 0.1397)
		(layer "B.Cu")
		(net "P2E_CPU_SAS_TX_DP4")
	)
	(segment
		(start 36.14166 -10.897362)
		(end 36.28136 -10.757662)
		(width 0.1397)
		(layer "B.Cu")
		(net "P2E_CPU_SAS_TX_DP4")
	)
	(segment
		(start 39.99992 -5.828538)
		(end 39.99992 -3.990848)
		(width 0.1397)
		(layer "B.Cu")
		(net "CPU_GBE_TX_C_DN0")
	)
	(segment
		(start 40.829992 -15.17015)
		(end 40.267382 -14.60754)
		(width 0.1397)
		(layer "B.Cu")
		(net "CPU_GBE_TX_C_DN0")
	)
	(segment
		(start 40.000682 -23.14956)
		(end 40.503602 -22.64664)
		(width 0.1397)
		(layer "B.Cu")
		(net "CPU_GBE_TX_C_DN0")
	)
	(segment
		(start 40.829992 -17.0561)
		(end 40.829992 -15.17015)
		(width 0.1397)
		(layer "B.Cu")
		(net "CPU_GBE_TX_C_DN0")
	)
	(segment
		(start 39.877492 -21.65985)
		(end 39.877492 -18.0086)
		(width 0.1397)
		(layer "B.Cu")
		(net "CPU_GBE_TX_C_DN0")
	)
	(segment
		(start 40.503602 -22.64664)
		(end 40.503602 -22.28596)
		(width 0.1397)
		(layer "B.Cu")
		(net "CPU_GBE_TX_C_DN0")
	)
	(segment
		(start 40.000682 -23.149814)
		(end 40.000682 -23.14956)
		(width 0.1397)
		(layer "B.Cu")
		(net "CPU_GBE_TX_C_DN0")
	)
	(segment
		(start 40.267382 -6.096)
		(end 39.99992 -5.828538)
		(width 0.1397)
		(layer "B.Cu")
		(net "CPU_GBE_TX_C_DN0")
	)
	(segment
		(start 39.877492 -18.0086)
		(end 40.829992 -17.0561)
		(width 0.1397)
		(layer "B.Cu")
		(net "CPU_GBE_TX_C_DN0")
	)
	(segment
		(start 40.503602 -22.28596)
		(end 39.877492 -21.65985)
		(width 0.1397)
		(layer "B.Cu")
		(net "CPU_GBE_TX_C_DN0")
	)
	(segment
		(start 40.267382 -14.60754)
		(end 40.267382 -6.096)
		(width 0.1397)
		(layer "B.Cu")
		(net "CPU_GBE_TX_C_DN0")
	)
	(segment
		(start 40.610282 -6.1087)
		(end 40.999918 -5.719064)
		(width 0.1397)
		(layer "B.Cu")
		(net "CPU_GBE_TX_C_DP0")
	)
	(segment
		(start 40.622982 -21.6916)
		(end 40.394382 -21.6916)
		(width 0.1397)
		(layer "B.Cu")
		(net "CPU_GBE_TX_C_DP0")
	)
	(segment
		(start 40.994838 -21.154644)
		(end 40.994838 -21.319744)
		(width 0.1397)
		(layer "B.Cu")
		(net "CPU_GBE_TX_C_DP0")
	)
	(segment
		(start 41.172892 -15.02791)
		(end 40.610282 -14.4653)
		(width 0.1397)
		(layer "B.Cu")
		(net "CPU_GBE_TX_C_DP0")
	)
	(segment
		(start 40.220392 -21.51761)
		(end 40.220392 -18.15084)
		(width 0.1397)
		(layer "B.Cu")
		(net "CPU_GBE_TX_C_DP0")
	)
	(segment
		(start 40.220392 -18.15084)
		(end 41.172892 -17.19834)
		(width 0.1397)
		(layer "B.Cu")
		(net "CPU_GBE_TX_C_DP0")
	)
	(segment
		(start 40.994838 -21.319744)
		(end 40.622982 -21.6916)
		(width 0.1397)
		(layer "B.Cu")
		(net "CPU_GBE_TX_C_DP0")
	)
	(segment
		(start 41.172892 -17.19834)
		(end 41.172892 -15.02791)
		(width 0.1397)
		(layer "B.Cu")
		(net "CPU_GBE_TX_C_DP0")
	)
	(segment
		(start 41.000172 -21.149564)
		(end 40.999918 -21.149564)
		(width 0.1397)
		(layer "B.Cu")
		(net "CPU_GBE_TX_C_DP0")
	)
	(segment
		(start 40.999918 -21.149564)
		(end 40.994838 -21.154644)
		(width 0.1397)
		(layer "B.Cu")
		(net "CPU_GBE_TX_C_DP0")
	)
	(segment
		(start 40.610282 -14.4653)
		(end 40.610282 -6.1087)
		(width 0.1397)
		(layer "B.Cu")
		(net "CPU_GBE_TX_C_DP0")
	)
	(segment
		(start 40.394382 -21.6916)
		(end 40.220392 -21.51761)
		(width 0.1397)
		(layer "B.Cu")
		(net "CPU_GBE_TX_C_DP0")
	)
	(segment
		(start 40.999918 -5.719064)
		(end 40.999918 -3.114548)
		(width 0.1397)
		(layer "B.Cu")
		(net "CPU_GBE_TX_C_DP0")
	)
	(segment
		(start 44.829222 -17.0561)
		(end 44.829222 -15.12824)
		(width 0.10795)
		(layer "B.Cu")
		(net "GBE_SMDATA_R")
	)
	(segment
		(start 43.999912 -5.747004)
		(end 43.999912 -3.114548)
		(width 0.10795)
		(layer "B.Cu")
		(net "GBE_SMDATA_R")
	)
	(segment
		(start 44.829222 -15.12824)
		(end 44.328588 -14.627606)
		(width 0.10795)
		(layer "B.Cu")
		(net "GBE_SMDATA_R")
	)
	(segment
		(start 43.876722 -18.0086)
		(end 44.829222 -17.0561)
		(width 0.10795)
		(layer "B.Cu")
		(net "GBE_SMDATA_R")
	)
	(segment
		(start 43.876722 -23.026878)
		(end 43.876722 -18.0086)
		(width 0.10795)
		(layer "B.Cu")
		(net "GBE_SMDATA_R")
	)
	(segment
		(start 43.999658 -23.149814)
		(end 43.876722 -23.026878)
		(width 0.10795)
		(layer "B.Cu")
		(net "GBE_SMDATA_R")
	)
	(segment
		(start 44.328588 -14.627606)
		(end 44.328588 -6.07568)
		(width 0.10795)
		(layer "B.Cu")
		(net "GBE_SMDATA_R")
	)
	(segment
		(start 43.999912 -23.149814)
		(end 43.999658 -23.149814)
		(width 0.10795)
		(layer "B.Cu")
		(net "GBE_SMDATA_R")
	)
	(segment
		(start 44.328588 -6.07568)
		(end 43.999912 -5.747004)
		(width 0.10795)
		(layer "B.Cu")
		(net "GBE_SMDATA_R")
	)
	(segment
		(start 45.000672 -21.149564)
		(end 45.000418 -21.149564)
		(width 0.10795)
		(layer "B.Cu")
		(net "GBE_SMBCLK_R")
	)
	(segment
		(start 44.219622 -20.368768)
		(end 44.219622 -18.15084)
		(width 0.10795)
		(layer "B.Cu")
		(net "GBE_SMBCLK_R")
	)
	(segment
		(start 45.172122 -14.986)
		(end 44.671488 -14.485366)
		(width 0.10795)
		(layer "B.Cu")
		(net "GBE_SMBCLK_R")
	)
	(segment
		(start 45.172122 -17.19834)
		(end 45.172122 -14.986)
		(width 0.10795)
		(layer "B.Cu")
		(net "GBE_SMBCLK_R")
	)
	(segment
		(start 44.219622 -18.15084)
		(end 45.172122 -17.19834)
		(width 0.10795)
		(layer "B.Cu")
		(net "GBE_SMBCLK_R")
	)
	(segment
		(start 44.99991 -5.747258)
		(end 44.99991 -3.114548)
		(width 0.10795)
		(layer "B.Cu")
		(net "GBE_SMBCLK_R")
	)
	(segment
		(start 44.671488 -6.07568)
		(end 44.99991 -5.747258)
		(width 0.10795)
		(layer "B.Cu")
		(net "GBE_SMBCLK_R")
	)
	(segment
		(start 44.671488 -14.485366)
		(end 44.671488 -6.07568)
		(width 0.10795)
		(layer "B.Cu")
		(net "GBE_SMBCLK_R")
	)
	(segment
		(start 45.000418 -21.149564)
		(end 44.219622 -20.368768)
		(width 0.10795)
		(layer "B.Cu")
		(net "GBE_SMBCLK_R")
	)
	(segment
		(start 55.992268 -22.331426)
		(end 55.874412 -22.21357)
		(width 0.1397)
		(layer "B.Cu")
		(net "SATA2_TX_C_DN0")
	)
	(segment
		(start 56.320182 -6.0198)
		(end 55.999888 -5.699506)
		(width 0.1397)
		(layer "B.Cu")
		(net "SATA2_TX_C_DN0")
	)
	(segment
		(start 56.320182 -14.3002)
		(end 56.320182 -6.0198)
		(width 0.1397)
		(layer "B.Cu")
		(net "SATA2_TX_C_DN0")
	)
	(segment
		(start 56.826912 -14.80693)
		(end 56.320182 -14.3002)
		(width 0.1397)
		(layer "B.Cu")
		(net "SATA2_TX_C_DN0")
	)
	(segment
		(start 56.000142 -23.149814)
		(end 55.999634 -23.14956)
		(width 0.1397)
		(layer "B.Cu")
		(net "SATA2_TX_C_DN0")
	)
	(segment
		(start 55.999634 -23.14956)
		(end 55.992268 -23.142194)
		(width 0.1397)
		(layer "B.Cu")
		(net "SATA2_TX_C_DN0")
	)
	(segment
		(start 56.826912 -17.0561)
		(end 56.826912 -14.80693)
		(width 0.1397)
		(layer "B.Cu")
		(net "SATA2_TX_C_DN0")
	)
	(segment
		(start 55.999888 -5.699506)
		(end 55.999888 -3.114548)
		(width 0.1397)
		(layer "B.Cu")
		(net "SATA2_TX_C_DN0")
	)
	(segment
		(start 55.874412 -22.21357)
		(end 55.874412 -18.0086)
		(width 0.1397)
		(layer "B.Cu")
		(net "SATA2_TX_C_DN0")
	)
	(segment
		(start 55.874412 -18.0086)
		(end 56.826912 -17.0561)
		(width 0.1397)
		(layer "B.Cu")
		(net "SATA2_TX_C_DN0")
	)
	(segment
		(start 55.992268 -23.142194)
		(end 55.992268 -22.331426)
		(width 0.1397)
		(layer "B.Cu")
		(net "SATA2_TX_C_DN0")
	)
	(segment
		(start 57.169812 -14.66469)
		(end 56.663082 -14.15796)
		(width 0.1397)
		(layer "B.Cu")
		(net "SATA2_TX_C_DP0")
	)
	(segment
		(start 56.421782 -22.2758)
		(end 56.217312 -22.07133)
		(width 0.1397)
		(layer "B.Cu")
		(net "SATA2_TX_C_DP0")
	)
	(segment
		(start 56.999632 -21.149564)
		(end 56.999378 -21.149564)
		(width 0.1397)
		(layer "B.Cu")
		(net "SATA2_TX_C_DP0")
	)
	(segment
		(start 56.217312 -22.07133)
		(end 56.217312 -18.15084)
		(width 0.1397)
		(layer "B.Cu")
		(net "SATA2_TX_C_DP0")
	)
	(segment
		(start 57.107582 -22.0472)
		(end 56.878982 -22.2758)
		(width 0.1397)
		(layer "B.Cu")
		(net "SATA2_TX_C_DP0")
	)
	(segment
		(start 57.169812 -17.19834)
		(end 57.169812 -14.66469)
		(width 0.1397)
		(layer "B.Cu")
		(net "SATA2_TX_C_DP0")
	)
	(segment
		(start 56.217312 -18.15084)
		(end 57.169812 -17.19834)
		(width 0.1397)
		(layer "B.Cu")
		(net "SATA2_TX_C_DP0")
	)
	(segment
		(start 56.999886 -5.746496)
		(end 56.999886 -3.990848)
		(width 0.1397)
		(layer "B.Cu")
		(net "SATA2_TX_C_DP0")
	)
	(segment
		(start 56.999378 -21.149564)
		(end 57.107582 -21.257768)
		(width 0.1397)
		(layer "B.Cu")
		(net "SATA2_TX_C_DP0")
	)
	(segment
		(start 56.663082 -6.0833)
		(end 56.999886 -5.746496)
		(width 0.1397)
		(layer "B.Cu")
		(net "SATA2_TX_C_DP0")
	)
	(segment
		(start 57.107582 -21.257768)
		(end 57.107582 -22.0472)
		(width 0.1397)
		(layer "B.Cu")
		(net "SATA2_TX_C_DP0")
	)
	(segment
		(start 56.878982 -22.2758)
		(end 56.421782 -22.2758)
		(width 0.1397)
		(layer "B.Cu")
		(net "SATA2_TX_C_DP0")
	)
	(segment
		(start 56.663082 -14.15796)
		(end 56.663082 -6.0833)
		(width 0.1397)
		(layer "B.Cu")
		(net "SATA2_TX_C_DP0")
	)
	(segment
		(start 59.873642 -21.8948)
		(end 59.873642 -18.0086)
		(width 0.1397)
		(layer "B.Cu")
		(net "P2E_CPU_SAS_TX_DN3")
	)
	(segment
		(start 59.873642 -18.0086)
		(end 60.826142 -17.0561)
		(width 0.1397)
		(layer "B.Cu")
		(net "P2E_CPU_SAS_TX_DN3")
	)
	(segment
		(start 60.328302 -6.07568)
		(end 59.99988 -5.747258)
		(width 0.1397)
		(layer "B.Cu")
		(net "P2E_CPU_SAS_TX_DN3")
	)
	(segment
		(start 60.000642 -23.149814)
		(end 60.178442 -22.972014)
		(width 0.1397)
		(layer "B.Cu")
		(net "P2E_CPU_SAS_TX_DN3")
	)
	(segment
		(start 59.66968 -9.63422)
		(end 60.188602 -9.63422)
		(width 0.1397)
		(layer "B.Cu")
		(net "P2E_CPU_SAS_TX_DN3")
	)
	(segment
		(start 60.826142 -15.12316)
		(end 60.188602 -14.48562)
		(width 0.1397)
		(layer "B.Cu")
		(net "P2E_CPU_SAS_TX_DN3")
	)
	(segment
		(start 59.72048 -13.24102)
		(end 60.188602 -13.24102)
		(width 0.1397)
		(layer "B.Cu")
		(net "P2E_CPU_SAS_TX_DN3")
	)
	(segment
		(start 59.66968 -12.68222)
		(end 59.32932 -12.34186)
		(width 0.1397)
		(layer "B.Cu")
		(net "P2E_CPU_SAS_TX_DN3")
	)
	(segment
		(start 60.188602 -9.63422)
		(end 60.328302 -9.49452)
		(width 0.1397)
		(layer "B.Cu")
		(net "P2E_CPU_SAS_TX_DN3")
	)
	(segment
		(start 59.39282 -13.56868)
		(end 59.72048 -13.24102)
		(width 0.1397)
		(layer "B.Cu")
		(net "P2E_CPU_SAS_TX_DN3")
	)
	(segment
		(start 60.328302 -11.29792)
		(end 60.328302 -11.01852)
		(width 0.1397)
		(layer "B.Cu")
		(net "P2E_CPU_SAS_TX_DN3")
	)
	(segment
		(start 59.66968 -10.87882)
		(end 59.32932 -10.53846)
		(width 0.1397)
		(layer "B.Cu")
		(net "P2E_CPU_SAS_TX_DN3")
	)
	(segment
		(start 60.178442 -22.1996)
		(end 59.873642 -21.8948)
		(width 0.1397)
		(layer "B.Cu")
		(net "P2E_CPU_SAS_TX_DN3")
	)
	(segment
		(start 60.188602 -14.48562)
		(end 59.72048 -14.48562)
		(width 0.1397)
		(layer "B.Cu")
		(net "P2E_CPU_SAS_TX_DN3")
	)
	(segment
		(start 60.328302 -12.82192)
		(end 60.188602 -12.68222)
		(width 0.1397)
		(layer "B.Cu")
		(net "P2E_CPU_SAS_TX_DN3")
	)
	(segment
		(start 60.826142 -17.0561)
		(end 60.826142 -15.12316)
		(width 0.1397)
		(layer "B.Cu")
		(net "P2E_CPU_SAS_TX_DN3")
	)
	(segment
		(start 60.328302 -9.49452)
		(end 60.328302 -6.07568)
		(width 0.1397)
		(layer "B.Cu")
		(net "P2E_CPU_SAS_TX_DN3")
	)
	(segment
		(start 59.66968 -11.43762)
		(end 60.188602 -11.43762)
		(width 0.1397)
		(layer "B.Cu")
		(net "P2E_CPU_SAS_TX_DN3")
	)
	(segment
		(start 60.188602 -10.87882)
		(end 59.66968 -10.87882)
		(width 0.1397)
		(layer "B.Cu")
		(net "P2E_CPU_SAS_TX_DN3")
	)
	(segment
		(start 59.32932 -10.53846)
		(end 59.32932 -9.97458)
		(width 0.1397)
		(layer "B.Cu")
		(net "P2E_CPU_SAS_TX_DN3")
	)
	(segment
		(start 59.32932 -11.77798)
		(end 59.66968 -11.43762)
		(width 0.1397)
		(layer "B.Cu")
		(net "P2E_CPU_SAS_TX_DN3")
	)
	(segment
		(start 59.99988 -5.747258)
		(end 59.99988 -3.114548)
		(width 0.1397)
		(layer "B.Cu")
		(net "P2E_CPU_SAS_TX_DN3")
	)
	(segment
		(start 60.178442 -22.972014)
		(end 60.178442 -22.1996)
		(width 0.1397)
		(layer "B.Cu")
		(net "P2E_CPU_SAS_TX_DN3")
	)
	(segment
		(start 59.39282 -14.15796)
		(end 59.39282 -13.56868)
		(width 0.1397)
		(layer "B.Cu")
		(net "P2E_CPU_SAS_TX_DN3")
	)
	(segment
		(start 60.188602 -12.68222)
		(end 59.66968 -12.68222)
		(width 0.1397)
		(layer "B.Cu")
		(net "P2E_CPU_SAS_TX_DN3")
	)
	(segment
		(start 60.328302 -13.10132)
		(end 60.328302 -12.82192)
		(width 0.1397)
		(layer "B.Cu")
		(net "P2E_CPU_SAS_TX_DN3")
	)
	(segment
		(start 59.72048 -14.48562)
		(end 59.39282 -14.15796)
		(width 0.1397)
		(layer "B.Cu")
		(net "P2E_CPU_SAS_TX_DN3")
	)
	(segment
		(start 60.188602 -11.43762)
		(end 60.328302 -11.29792)
		(width 0.1397)
		(layer "B.Cu")
		(net "P2E_CPU_SAS_TX_DN3")
	)
	(segment
		(start 60.328302 -11.01852)
		(end 60.188602 -10.87882)
		(width 0.1397)
		(layer "B.Cu")
		(net "P2E_CPU_SAS_TX_DN3")
	)
	(segment
		(start 59.32932 -12.34186)
		(end 59.32932 -11.77798)
		(width 0.1397)
		(layer "B.Cu")
		(net "P2E_CPU_SAS_TX_DN3")
	)
	(segment
		(start 60.188602 -13.24102)
		(end 60.328302 -13.10132)
		(width 0.1397)
		(layer "B.Cu")
		(net "P2E_CPU_SAS_TX_DN3")
	)
	(segment
		(start 59.32932 -9.97458)
		(end 59.66968 -9.63422)
		(width 0.1397)
		(layer "B.Cu")
		(net "P2E_CPU_SAS_TX_DN3")
	)
	(segment
		(start 59.73572 -13.71092)
		(end 59.86272 -13.58392)
		(width 0.1397)
		(layer "B.Cu")
		(net "P2E_CPU_SAS_TX_DP3")
	)
	(segment
		(start 60.671202 -13.24356)
		(end 60.671202 -12.67968)
		(width 0.1397)
		(layer "B.Cu")
		(net "P2E_CPU_SAS_TX_DP3")
	)
	(segment
		(start 60.671202 -6.07568)
		(end 60.999878 -5.747004)
		(width 0.1397)
		(layer "B.Cu")
		(net "P2E_CPU_SAS_TX_DP3")
	)
	(segment
		(start 60.671202 -9.63676)
		(end 60.671202 -6.07568)
		(width 0.1397)
		(layer "B.Cu")
		(net "P2E_CPU_SAS_TX_DP3")
	)
	(segment
		(start 60.460382 -21.9964)
		(end 60.216542 -21.75256)
		(width 0.1397)
		(layer "B.Cu")
		(net "P2E_CPU_SAS_TX_DP3")
	)
	(segment
		(start 59.86272 -14.14272)
		(end 59.73572 -14.01572)
		(width 0.1397)
		(layer "B.Cu")
		(net "P2E_CPU_SAS_TX_DP3")
	)
	(segment
		(start 59.67222 -12.19962)
		(end 59.67222 -11.92022)
		(width 0.1397)
		(layer "B.Cu")
		(net "P2E_CPU_SAS_TX_DP3")
	)
	(segment
		(start 59.81192 -9.97712)
		(end 60.330842 -9.97712)
		(width 0.1397)
		(layer "B.Cu")
		(net "P2E_CPU_SAS_TX_DP3")
	)
	(segment
		(start 60.330842 -13.58392)
		(end 60.671202 -13.24356)
		(width 0.1397)
		(layer "B.Cu")
		(net "P2E_CPU_SAS_TX_DP3")
	)
	(segment
		(start 61.000132 -21.149564)
		(end 60.990988 -21.149564)
		(width 0.1397)
		(layer "B.Cu")
		(net "P2E_CPU_SAS_TX_DP3")
	)
	(segment
		(start 60.330842 -11.78052)
		(end 60.671202 -11.44016)
		(width 0.1397)
		(layer "B.Cu")
		(net "P2E_CPU_SAS_TX_DP3")
	)
	(segment
		(start 60.990988 -21.793454)
		(end 60.788042 -21.9964)
		(width 0.1397)
		(layer "B.Cu")
		(net "P2E_CPU_SAS_TX_DP3")
	)
	(segment
		(start 60.330842 -10.53592)
		(end 59.81192 -10.53592)
		(width 0.1397)
		(layer "B.Cu")
		(net "P2E_CPU_SAS_TX_DP3")
	)
	(segment
		(start 60.216542 -21.75256)
		(end 60.216542 -18.15084)
		(width 0.1397)
		(layer "B.Cu")
		(net "P2E_CPU_SAS_TX_DP3")
	)
	(segment
		(start 60.330842 -14.14272)
		(end 59.86272 -14.14272)
		(width 0.1397)
		(layer "B.Cu")
		(net "P2E_CPU_SAS_TX_DP3")
	)
	(segment
		(start 59.81192 -10.53592)
		(end 59.67222 -10.39622)
		(width 0.1397)
		(layer "B.Cu")
		(net "P2E_CPU_SAS_TX_DP3")
	)
	(segment
		(start 59.67222 -11.92022)
		(end 59.81192 -11.78052)
		(width 0.1397)
		(layer "B.Cu")
		(net "P2E_CPU_SAS_TX_DP3")
	)
	(segment
		(start 60.671202 -12.67968)
		(end 60.330842 -12.33932)
		(width 0.1397)
		(layer "B.Cu")
		(net "P2E_CPU_SAS_TX_DP3")
	)
	(segment
		(start 60.788042 -21.9964)
		(end 60.460382 -21.9964)
		(width 0.1397)
		(layer "B.Cu")
		(net "P2E_CPU_SAS_TX_DP3")
	)
	(segment
		(start 59.73572 -14.01572)
		(end 59.73572 -13.71092)
		(width 0.1397)
		(layer "B.Cu")
		(net "P2E_CPU_SAS_TX_DP3")
	)
	(segment
		(start 61.169042 -14.98092)
		(end 60.330842 -14.14272)
		(width 0.1397)
		(layer "B.Cu")
		(net "P2E_CPU_SAS_TX_DP3")
	)
	(segment
		(start 60.216542 -18.15084)
		(end 61.169042 -17.19834)
		(width 0.1397)
		(layer "B.Cu")
		(net "P2E_CPU_SAS_TX_DP3")
	)
	(segment
		(start 60.671202 -11.44016)
		(end 60.671202 -10.87628)
		(width 0.1397)
		(layer "B.Cu")
		(net "P2E_CPU_SAS_TX_DP3")
	)
	(segment
		(start 61.169042 -17.19834)
		(end 61.169042 -14.98092)
		(width 0.1397)
		(layer "B.Cu")
		(net "P2E_CPU_SAS_TX_DP3")
	)
	(segment
		(start 59.81192 -11.78052)
		(end 60.330842 -11.78052)
		(width 0.1397)
		(layer "B.Cu")
		(net "P2E_CPU_SAS_TX_DP3")
	)
	(segment
		(start 59.86272 -13.58392)
		(end 60.330842 -13.58392)
		(width 0.1397)
		(layer "B.Cu")
		(net "P2E_CPU_SAS_TX_DP3")
	)
	(segment
		(start 60.330842 -12.33932)
		(end 59.81192 -12.33932)
		(width 0.1397)
		(layer "B.Cu")
		(net "P2E_CPU_SAS_TX_DP3")
	)
	(segment
		(start 60.990988 -21.149564)
		(end 60.990988 -21.793454)
		(width 0.1397)
		(layer "B.Cu")
		(net "P2E_CPU_SAS_TX_DP3")
	)
	(segment
		(start 60.330842 -9.97712)
		(end 60.671202 -9.63676)
		(width 0.1397)
		(layer "B.Cu")
		(net "P2E_CPU_SAS_TX_DP3")
	)
	(segment
		(start 59.67222 -10.39622)
		(end 59.67222 -10.11682)
		(width 0.1397)
		(layer "B.Cu")
		(net "P2E_CPU_SAS_TX_DP3")
	)
	(segment
		(start 59.81192 -12.33932)
		(end 59.67222 -12.19962)
		(width 0.1397)
		(layer "B.Cu")
		(net "P2E_CPU_SAS_TX_DP3")
	)
	(segment
		(start 60.999878 -5.747004)
		(end 60.999878 -3.114548)
		(width 0.1397)
		(layer "B.Cu")
		(net "P2E_CPU_SAS_TX_DP3")
	)
	(segment
		(start 59.67222 -10.11682)
		(end 59.81192 -9.97712)
		(width 0.1397)
		(layer "B.Cu")
		(net "P2E_CPU_SAS_TX_DP3")
	)
	(segment
		(start 60.671202 -10.87628)
		(end 60.330842 -10.53592)
		(width 0.1397)
		(layer "B.Cu")
		(net "P2E_CPU_SAS_TX_DP3")
	)
	(segment
		(start 61.90996 -11.815572)
		(end 62.25032 -11.475212)
		(width 0.1397)
		(layer "B.Cu")
		(net "P2E_CPU_SAS_TX_DN2")
	)
	(segment
		(start 62.25032 -12.719812)
		(end 61.90996 -12.379452)
		(width 0.1397)
		(layer "B.Cu")
		(net "P2E_CPU_SAS_TX_DN2")
	)
	(segment
		(start 62.822582 -13.138912)
		(end 62.822582 -12.859512)
		(width 0.1397)
		(layer "B.Cu")
		(net "P2E_CPU_SAS_TX_DN2")
	)
	(segment
		(start 63.872872 -18.32229)
		(end 62.822582 -17.272)
		(width 0.1397)
		(layer "B.Cu")
		(net "P2E_CPU_SAS_TX_DN2")
	)
	(segment
		(start 62.21222 -14.523212)
		(end 61.88456 -14.195552)
		(width 0.1397)
		(layer "B.Cu")
		(net "P2E_CPU_SAS_TX_DN2")
	)
	(segment
		(start 62.682882 -10.916412)
		(end 62.25032 -10.916412)
		(width 0.1397)
		(layer "B.Cu")
		(net "P2E_CPU_SAS_TX_DN2")
	)
	(segment
		(start 62.682882 -12.719812)
		(end 62.25032 -12.719812)
		(width 0.1397)
		(layer "B.Cu")
		(net "P2E_CPU_SAS_TX_DN2")
	)
	(segment
		(start 61.90996 -12.379452)
		(end 61.90996 -11.815572)
		(width 0.1397)
		(layer "B.Cu")
		(net "P2E_CPU_SAS_TX_DN2")
	)
	(segment
		(start 61.90996 -10.576052)
		(end 61.90996 -10.012172)
		(width 0.1397)
		(layer "B.Cu")
		(net "P2E_CPU_SAS_TX_DN2")
	)
	(segment
		(start 62.682882 -11.475212)
		(end 62.822582 -11.335512)
		(width 0.1397)
		(layer "B.Cu")
		(net "P2E_CPU_SAS_TX_DN2")
	)
	(segment
		(start 64.177672 -22.1996)
		(end 63.872872 -21.8948)
		(width 0.1397)
		(layer "B.Cu")
		(net "P2E_CPU_SAS_TX_DN2")
	)
	(segment
		(start 62.822582 -17.272)
		(end 62.822582 -14.662912)
		(width 0.1397)
		(layer "B.Cu")
		(net "P2E_CPU_SAS_TX_DN2")
	)
	(segment
		(start 64.328294 -6.07568)
		(end 63.999872 -5.747258)
		(width 0.1397)
		(layer "B.Cu")
		(net "P2E_CPU_SAS_TX_DN2")
	)
	(segment
		(start 61.88456 -13.606272)
		(end 62.21222 -13.278612)
		(width 0.1397)
		(layer "B.Cu")
		(net "P2E_CPU_SAS_TX_DN2")
	)
	(segment
		(start 64.328294 -8.0264)
		(end 64.328294 -6.07568)
		(width 0.1397)
		(layer "B.Cu")
		(net "P2E_CPU_SAS_TX_DN2")
	)
	(segment
		(start 62.822582 -11.056112)
		(end 62.682882 -10.916412)
		(width 0.1397)
		(layer "B.Cu")
		(net "P2E_CPU_SAS_TX_DN2")
	)
	(segment
		(start 61.88456 -14.195552)
		(end 61.88456 -13.606272)
		(width 0.1397)
		(layer "B.Cu")
		(net "P2E_CPU_SAS_TX_DN2")
	)
	(segment
		(start 62.25032 -9.671812)
		(end 62.682882 -9.671812)
		(width 0.1397)
		(layer "B.Cu")
		(net "P2E_CPU_SAS_TX_DN2")
	)
	(segment
		(start 64.177672 -22.96287)
		(end 64.177672 -22.1996)
		(width 0.1397)
		(layer "B.Cu")
		(net "P2E_CPU_SAS_TX_DN2")
	)
	(segment
		(start 61.90996 -10.012172)
		(end 62.25032 -9.671812)
		(width 0.1397)
		(layer "B.Cu")
		(net "P2E_CPU_SAS_TX_DN2")
	)
	(segment
		(start 62.822582 -11.335512)
		(end 62.822582 -11.056112)
		(width 0.1397)
		(layer "B.Cu")
		(net "P2E_CPU_SAS_TX_DN2")
	)
	(segment
		(start 62.25032 -11.475212)
		(end 62.682882 -11.475212)
		(width 0.1397)
		(layer "B.Cu")
		(net "P2E_CPU_SAS_TX_DN2")
	)
	(segment
		(start 63.999872 -23.149814)
		(end 63.990728 -23.149814)
		(width 0.1397)
		(layer "B.Cu")
		(net "P2E_CPU_SAS_TX_DN2")
	)
	(segment
		(start 63.872872 -21.8948)
		(end 63.872872 -18.32229)
		(width 0.1397)
		(layer "B.Cu")
		(net "P2E_CPU_SAS_TX_DN2")
	)
	(segment
		(start 62.682882 -14.523212)
		(end 62.21222 -14.523212)
		(width 0.1397)
		(layer "B.Cu")
		(net "P2E_CPU_SAS_TX_DN2")
	)
	(segment
		(start 62.682882 -9.671812)
		(end 64.328294 -8.0264)
		(width 0.1397)
		(layer "B.Cu")
		(net "P2E_CPU_SAS_TX_DN2")
	)
	(segment
		(start 62.822582 -14.662912)
		(end 62.682882 -14.523212)
		(width 0.1397)
		(layer "B.Cu")
		(net "P2E_CPU_SAS_TX_DN2")
	)
	(segment
		(start 62.682882 -13.278612)
		(end 62.822582 -13.138912)
		(width 0.1397)
		(layer "B.Cu")
		(net "P2E_CPU_SAS_TX_DN2")
	)
	(segment
		(start 62.21222 -13.278612)
		(end 62.682882 -13.278612)
		(width 0.1397)
		(layer "B.Cu")
		(net "P2E_CPU_SAS_TX_DN2")
	)
	(segment
		(start 62.25032 -10.916412)
		(end 61.90996 -10.576052)
		(width 0.1397)
		(layer "B.Cu")
		(net "P2E_CPU_SAS_TX_DN2")
	)
	(segment
		(start 63.990728 -23.149814)
		(end 64.177672 -22.96287)
		(width 0.1397)
		(layer "B.Cu")
		(net "P2E_CPU_SAS_TX_DN2")
	)
	(segment
		(start 62.822582 -12.859512)
		(end 62.682882 -12.719812)
		(width 0.1397)
		(layer "B.Cu")
		(net "P2E_CPU_SAS_TX_DN2")
	)
	(segment
		(start 63.999872 -5.747258)
		(end 63.999872 -3.114548)
		(width 0.1397)
		(layer "B.Cu")
		(net "P2E_CPU_SAS_TX_DN2")
	)
	(segment
		(start 63.165482 -10.913872)
		(end 62.825122 -10.573512)
		(width 0.1397)
		(layer "B.Cu")
		(net "P2E_CPU_SAS_TX_DP2")
	)
	(segment
		(start 63.165482 -11.477752)
		(end 63.165482 -10.913872)
		(width 0.1397)
		(layer "B.Cu")
		(net "P2E_CPU_SAS_TX_DP2")
	)
	(segment
		(start 62.25286 -10.433812)
		(end 62.25286 -10.154412)
		(width 0.1397)
		(layer "B.Cu")
		(net "P2E_CPU_SAS_TX_DP2")
	)
	(segment
		(start 63.165482 -14.520672)
		(end 62.825122 -14.180312)
		(width 0.1397)
		(layer "B.Cu")
		(net "P2E_CPU_SAS_TX_DP2")
	)
	(segment
		(start 62.25286 -10.154412)
		(end 62.39256 -10.014712)
		(width 0.1397)
		(layer "B.Cu")
		(net "P2E_CPU_SAS_TX_DP2")
	)
	(segment
		(start 62.39256 -10.014712)
		(end 62.825122 -10.014712)
		(width 0.1397)
		(layer "B.Cu")
		(net "P2E_CPU_SAS_TX_DP2")
	)
	(segment
		(start 62.825122 -12.376912)
		(end 62.39256 -12.376912)
		(width 0.1397)
		(layer "B.Cu")
		(net "P2E_CPU_SAS_TX_DP2")
	)
	(segment
		(start 62.22746 -13.748512)
		(end 62.35446 -13.621512)
		(width 0.1397)
		(layer "B.Cu")
		(net "P2E_CPU_SAS_TX_DP2")
	)
	(segment
		(start 62.25286 -12.237212)
		(end 62.25286 -11.957812)
		(width 0.1397)
		(layer "B.Cu")
		(net "P2E_CPU_SAS_TX_DP2")
	)
	(segment
		(start 62.39256 -11.818112)
		(end 62.825122 -11.818112)
		(width 0.1397)
		(layer "B.Cu")
		(net "P2E_CPU_SAS_TX_DP2")
	)
	(segment
		(start 62.825122 -10.573512)
		(end 62.39256 -10.573512)
		(width 0.1397)
		(layer "B.Cu")
		(net "P2E_CPU_SAS_TX_DP2")
	)
	(segment
		(start 63.165482 -12.717272)
		(end 62.825122 -12.376912)
		(width 0.1397)
		(layer "B.Cu")
		(net "P2E_CPU_SAS_TX_DP2")
	)
	(segment
		(start 62.22746 -14.053312)
		(end 62.22746 -13.748512)
		(width 0.1397)
		(layer "B.Cu")
		(net "P2E_CPU_SAS_TX_DP2")
	)
	(segment
		(start 63.165482 -13.281152)
		(end 63.165482 -12.717272)
		(width 0.1397)
		(layer "B.Cu")
		(net "P2E_CPU_SAS_TX_DP2")
	)
	(segment
		(start 62.35446 -13.621512)
		(end 62.825122 -13.621512)
		(width 0.1397)
		(layer "B.Cu")
		(net "P2E_CPU_SAS_TX_DP2")
	)
	(segment
		(start 64.990218 -21.793454)
		(end 64.787272 -21.9964)
		(width 0.1397)
		(layer "B.Cu")
		(net "P2E_CPU_SAS_TX_DP2")
	)
	(segment
		(start 62.825122 -11.818112)
		(end 63.165482 -11.477752)
		(width 0.1397)
		(layer "B.Cu")
		(net "P2E_CPU_SAS_TX_DP2")
	)
	(segment
		(start 64.671194 -8.16864)
		(end 64.671194 -6.07568)
		(width 0.1397)
		(layer "B.Cu")
		(net "P2E_CPU_SAS_TX_DP2")
	)
	(segment
		(start 65.000632 -21.149564)
		(end 64.990218 -21.149564)
		(width 0.1397)
		(layer "B.Cu")
		(net "P2E_CPU_SAS_TX_DP2")
	)
	(segment
		(start 62.825122 -10.014712)
		(end 64.671194 -8.16864)
		(width 0.1397)
		(layer "B.Cu")
		(net "P2E_CPU_SAS_TX_DP2")
	)
	(segment
		(start 64.215772 -18.18005)
		(end 63.165482 -17.12976)
		(width 0.1397)
		(layer "B.Cu")
		(net "P2E_CPU_SAS_TX_DP2")
	)
	(segment
		(start 64.215772 -21.75256)
		(end 64.215772 -18.18005)
		(width 0.1397)
		(layer "B.Cu")
		(net "P2E_CPU_SAS_TX_DP2")
	)
	(segment
		(start 62.25286 -11.957812)
		(end 62.39256 -11.818112)
		(width 0.1397)
		(layer "B.Cu")
		(net "P2E_CPU_SAS_TX_DP2")
	)
	(segment
		(start 64.459612 -21.9964)
		(end 64.215772 -21.75256)
		(width 0.1397)
		(layer "B.Cu")
		(net "P2E_CPU_SAS_TX_DP2")
	)
	(segment
		(start 63.165482 -17.12976)
		(end 63.165482 -14.520672)
		(width 0.1397)
		(layer "B.Cu")
		(net "P2E_CPU_SAS_TX_DP2")
	)
	(segment
		(start 64.990218 -21.149564)
		(end 64.990218 -21.793454)
		(width 0.1397)
		(layer "B.Cu")
		(net "P2E_CPU_SAS_TX_DP2")
	)
	(segment
		(start 64.787272 -21.9964)
		(end 64.459612 -21.9964)
		(width 0.1397)
		(layer "B.Cu")
		(net "P2E_CPU_SAS_TX_DP2")
	)
	(segment
		(start 62.825122 -13.621512)
		(end 63.165482 -13.281152)
		(width 0.1397)
		(layer "B.Cu")
		(net "P2E_CPU_SAS_TX_DP2")
	)
	(segment
		(start 62.39256 -10.573512)
		(end 62.25286 -10.433812)
		(width 0.1397)
		(layer "B.Cu")
		(net "P2E_CPU_SAS_TX_DP2")
	)
	(segment
		(start 62.825122 -14.180312)
		(end 62.35446 -14.180312)
		(width 0.1397)
		(layer "B.Cu")
		(net "P2E_CPU_SAS_TX_DP2")
	)
	(segment
		(start 64.671194 -6.07568)
		(end 64.99987 -5.747004)
		(width 0.1397)
		(layer "B.Cu")
		(net "P2E_CPU_SAS_TX_DP2")
	)
	(segment
		(start 62.39256 -12.376912)
		(end 62.25286 -12.237212)
		(width 0.1397)
		(layer "B.Cu")
		(net "P2E_CPU_SAS_TX_DP2")
	)
	(segment
		(start 64.99987 -5.747004)
		(end 64.99987 -3.114548)
		(width 0.1397)
		(layer "B.Cu")
		(net "P2E_CPU_SAS_TX_DP2")
	)
	(segment
		(start 62.35446 -14.180312)
		(end 62.22746 -14.053312)
		(width 0.1397)
		(layer "B.Cu")
		(net "P2E_CPU_SAS_TX_DP2")
	)
	(segment
		(start 65.494662 -8.78078)
		(end 67.427602 -8.78078)
		(width 0.1397)
		(layer "B.Cu")
		(net "P2E_CPU_SAS_TX_DN1")
	)
	(segment
		(start 67.989958 -23.149814)
		(end 68.176902 -22.96287)
		(width 0.1397)
		(layer "B.Cu")
		(net "P2E_CPU_SAS_TX_DN1")
	)
	(segment
		(start 68.328286 -7.880096)
		(end 68.328286 -6.07568)
		(width 0.1397)
		(layer "B.Cu")
		(net "P2E_CPU_SAS_TX_DN1")
	)
	(segment
		(start 67.999864 -5.747258)
		(end 67.999864 -3.114548)
		(width 0.1397)
		(layer "B.Cu")
		(net "P2E_CPU_SAS_TX_DN1")
	)
	(segment
		(start 68.000372 -23.149814)
		(end 67.989958 -23.149814)
		(width 0.1397)
		(layer "B.Cu")
		(net "P2E_CPU_SAS_TX_DN1")
	)
	(segment
		(start 67.188842 -20.15236)
		(end 66.75374 -20.15236)
		(width 0.1397)
		(layer "B.Cu")
		(net "P2E_CPU_SAS_TX_DN1")
	)
	(segment
		(start 67.427602 -8.78078)
		(end 68.328286 -7.880096)
		(width 0.1397)
		(layer "B.Cu")
		(net "P2E_CPU_SAS_TX_DN1")
	)
	(segment
		(start 64.905382 -16.2306)
		(end 63.863982 -15.1892)
		(width 0.1397)
		(layer "B.Cu")
		(net "P2E_CPU_SAS_TX_DN1")
	)
	(segment
		(start 68.176902 -22.1996)
		(end 67.872102 -21.8948)
		(width 0.1397)
		(layer "B.Cu")
		(net "P2E_CPU_SAS_TX_DN1")
	)
	(segment
		(start 67.872102 -20.83562)
		(end 67.188842 -20.15236)
		(width 0.1397)
		(layer "B.Cu")
		(net "P2E_CPU_SAS_TX_DN1")
	)
	(segment
		(start 68.176902 -22.96287)
		(end 68.176902 -22.1996)
		(width 0.1397)
		(layer "B.Cu")
		(net "P2E_CPU_SAS_TX_DN1")
	)
	(segment
		(start 67.872102 -21.8948)
		(end 67.872102 -20.83562)
		(width 0.1397)
		(layer "B.Cu")
		(net "P2E_CPU_SAS_TX_DN1")
	)
	(segment
		(start 63.863982 -15.1892)
		(end 63.863982 -10.41146)
		(width 0.1397)
		(layer "B.Cu")
		(net "P2E_CPU_SAS_TX_DN1")
	)
	(segment
		(start 68.328286 -6.07568)
		(end 67.999864 -5.747258)
		(width 0.1397)
		(layer "B.Cu")
		(net "P2E_CPU_SAS_TX_DN1")
	)
	(segment
		(start 65.817242 -18.15846)
		(end 64.905382 -17.2466)
		(width 0.1397)
		(layer "B.Cu")
		(net "P2E_CPU_SAS_TX_DN1")
	)
	(segment
		(start 63.863982 -10.41146)
		(end 65.494662 -8.78078)
		(width 0.1397)
		(layer "B.Cu")
		(net "P2E_CPU_SAS_TX_DN1")
	)
	(segment
		(start 64.905382 -17.2466)
		(end 64.905382 -16.2306)
		(width 0.1397)
		(layer "B.Cu")
		(net "P2E_CPU_SAS_TX_DN1")
	)
	(segment
		(start 65.817242 -19.215862)
		(end 65.817242 -18.15846)
		(width 0.1397)
		(layer "B.Cu")
		(net "P2E_CPU_SAS_TX_DN1")
	)
	(segment
		(start 66.75374 -20.15236)
		(end 65.817242 -19.215862)
		(width 0.1397)
		(layer "B.Cu")
		(net "P2E_CPU_SAS_TX_DN1")
	)
	(segment
		(start 64.206882 -10.5537)
		(end 65.636902 -9.12368)
		(width 0.1397)
		(layer "B.Cu")
		(net "P2E_CPU_SAS_TX_DP1")
	)
	(segment
		(start 64.206882 -15.04696)
		(end 64.206882 -10.5537)
		(width 0.1397)
		(layer "B.Cu")
		(net "P2E_CPU_SAS_TX_DP1")
	)
	(segment
		(start 66.89598 -19.80946)
		(end 66.160142 -19.073622)
		(width 0.1397)
		(layer "B.Cu")
		(net "P2E_CPU_SAS_TX_DP1")
	)
	(segment
		(start 68.671186 -6.07568)
		(end 68.999862 -5.747004)
		(width 0.1397)
		(layer "B.Cu")
		(net "P2E_CPU_SAS_TX_DP1")
	)
	(segment
		(start 68.999862 -5.747004)
		(end 68.999862 -3.114548)
		(width 0.1397)
		(layer "B.Cu")
		(net "P2E_CPU_SAS_TX_DP1")
	)
	(segment
		(start 65.248282 -17.10436)
		(end 65.248282 -16.08836)
		(width 0.1397)
		(layer "B.Cu")
		(net "P2E_CPU_SAS_TX_DP1")
	)
	(segment
		(start 65.636902 -9.12368)
		(end 67.569842 -9.12368)
		(width 0.1397)
		(layer "B.Cu")
		(net "P2E_CPU_SAS_TX_DP1")
	)
	(segment
		(start 68.999862 -21.149564)
		(end 68.989448 -21.149564)
		(width 0.1397)
		(layer "B.Cu")
		(net "P2E_CPU_SAS_TX_DP1")
	)
	(segment
		(start 65.248282 -16.08836)
		(end 64.206882 -15.04696)
		(width 0.1397)
		(layer "B.Cu")
		(net "P2E_CPU_SAS_TX_DP1")
	)
	(segment
		(start 68.786502 -21.9964)
		(end 68.458842 -21.9964)
		(width 0.1397)
		(layer "B.Cu")
		(net "P2E_CPU_SAS_TX_DP1")
	)
	(segment
		(start 68.989448 -21.149564)
		(end 68.989448 -21.793454)
		(width 0.1397)
		(layer "B.Cu")
		(net "P2E_CPU_SAS_TX_DP1")
	)
	(segment
		(start 67.331082 -19.80946)
		(end 66.89598 -19.80946)
		(width 0.1397)
		(layer "B.Cu")
		(net "P2E_CPU_SAS_TX_DP1")
	)
	(segment
		(start 67.569842 -9.12368)
		(end 68.671186 -8.022336)
		(width 0.1397)
		(layer "B.Cu")
		(net "P2E_CPU_SAS_TX_DP1")
	)
	(segment
		(start 68.215002 -20.69338)
		(end 67.331082 -19.80946)
		(width 0.1397)
		(layer "B.Cu")
		(net "P2E_CPU_SAS_TX_DP1")
	)
	(segment
		(start 66.160142 -18.01622)
		(end 65.248282 -17.10436)
		(width 0.1397)
		(layer "B.Cu")
		(net "P2E_CPU_SAS_TX_DP1")
	)
	(segment
		(start 66.160142 -19.073622)
		(end 66.160142 -18.01622)
		(width 0.1397)
		(layer "B.Cu")
		(net "P2E_CPU_SAS_TX_DP1")
	)
	(segment
		(start 68.458842 -21.9964)
		(end 68.215002 -21.75256)
		(width 0.1397)
		(layer "B.Cu")
		(net "P2E_CPU_SAS_TX_DP1")
	)
	(segment
		(start 68.215002 -21.75256)
		(end 68.215002 -20.69338)
		(width 0.1397)
		(layer "B.Cu")
		(net "P2E_CPU_SAS_TX_DP1")
	)
	(segment
		(start 68.671186 -8.022336)
		(end 68.671186 -6.07568)
		(width 0.1397)
		(layer "B.Cu")
		(net "P2E_CPU_SAS_TX_DP1")
	)
	(segment
		(start 68.989448 -21.793454)
		(end 68.786502 -21.9964)
		(width 0.1397)
		(layer "B.Cu")
		(net "P2E_CPU_SAS_TX_DP1")
	)
	(segment
		(start 69.7611 -8.81126)
		(end 72.06996 -8.81126)
		(width 0.1397)
		(layer "B.Cu")
		(net "P2E_CPU_SAS_TX_DN0")
	)
	(segment
		(start 71.50608 -20.066)
		(end 70.612 -20.066)
		(width 0.1397)
		(layer "B.Cu")
		(net "P2E_CPU_SAS_TX_DN0")
	)
	(segment
		(start 72.328532 -6.07568)
		(end 71.999856 -5.747004)
		(width 0.1397)
		(layer "B.Cu")
		(net "P2E_CPU_SAS_TX_DN0")
	)
	(segment
		(start 70.836282 -16.14424)
		(end 70.12813 -15.436088)
		(width 0.1397)
		(layer "B.Cu")
		(net "P2E_CPU_SAS_TX_DN0")
	)
	(segment
		(start 71.814182 -21.8694)
		(end 71.814182 -20.374102)
		(width 0.1397)
		(layer "B.Cu")
		(net "P2E_CPU_SAS_TX_DN0")
	)
	(segment
		(start 69.8373 -18.06702)
		(end 70.836282 -17.068038)
		(width 0.1397)
		(layer "B.Cu")
		(net "P2E_CPU_SAS_TX_DN0")
	)
	(segment
		(start 69.39788 -9.17448)
		(end 69.7611 -8.81126)
		(width 0.1397)
		(layer "B.Cu")
		(net "P2E_CPU_SAS_TX_DN0")
	)
	(segment
		(start 71.999602 -23.149814)
		(end 71.999602 -23.14956)
		(width 0.1397)
		(layer "B.Cu")
		(net "P2E_CPU_SAS_TX_DN0")
	)
	(segment
		(start 71.999602 -23.14956)
		(end 72.144382 -23.00478)
		(width 0.1397)
		(layer "B.Cu")
		(net "P2E_CPU_SAS_TX_DN0")
	)
	(segment
		(start 69.8373 -19.2913)
		(end 69.8373 -18.06702)
		(width 0.1397)
		(layer "B.Cu")
		(net "P2E_CPU_SAS_TX_DN0")
	)
	(segment
		(start 71.999856 -5.747004)
		(end 71.999856 -3.114548)
		(width 0.1397)
		(layer "B.Cu")
		(net "P2E_CPU_SAS_TX_DN0")
	)
	(segment
		(start 72.144382 -22.1996)
		(end 71.814182 -21.8694)
		(width 0.1397)
		(layer "B.Cu")
		(net "P2E_CPU_SAS_TX_DN0")
	)
	(segment
		(start 72.144382 -23.00478)
		(end 72.144382 -22.1996)
		(width 0.1397)
		(layer "B.Cu")
		(net "P2E_CPU_SAS_TX_DN0")
	)
	(segment
		(start 72.328532 -8.552688)
		(end 72.328532 -6.07568)
		(width 0.1397)
		(layer "B.Cu")
		(net "P2E_CPU_SAS_TX_DN0")
	)
	(segment
		(start 70.12813 -10.45083)
		(end 69.39788 -9.72058)
		(width 0.1397)
		(layer "B.Cu")
		(net "P2E_CPU_SAS_TX_DN0")
	)
	(segment
		(start 72.06996 -8.81126)
		(end 72.328532 -8.552688)
		(width 0.1397)
		(layer "B.Cu")
		(net "P2E_CPU_SAS_TX_DN0")
	)
	(segment
		(start 71.814182 -20.374102)
		(end 71.50608 -20.066)
		(width 0.1397)
		(layer "B.Cu")
		(net "P2E_CPU_SAS_TX_DN0")
	)
	(segment
		(start 69.39788 -9.72058)
		(end 69.39788 -9.17448)
		(width 0.1397)
		(layer "B.Cu")
		(net "P2E_CPU_SAS_TX_DN0")
	)
	(segment
		(start 70.12813 -15.436088)
		(end 70.12813 -10.45083)
		(width 0.1397)
		(layer "B.Cu")
		(net "P2E_CPU_SAS_TX_DN0")
	)
	(segment
		(start 70.836282 -17.068038)
		(end 70.836282 -16.14424)
		(width 0.1397)
		(layer "B.Cu")
		(net "P2E_CPU_SAS_TX_DN0")
	)
	(segment
		(start 70.612 -20.066)
		(end 69.8373 -19.2913)
		(width 0.1397)
		(layer "B.Cu")
		(net "P2E_CPU_SAS_TX_DN0")
	)
	(segment
		(start 70.1802 -18.20926)
		(end 71.179182 -17.210278)
		(width 0.1397)
		(layer "B.Cu")
		(net "P2E_CPU_SAS_TX_DP0")
	)
	(segment
		(start 69.74078 -9.31672)
		(end 69.90334 -9.15416)
		(width 0.1397)
		(layer "B.Cu")
		(net "P2E_CPU_SAS_TX_DP0")
	)
	(segment
		(start 72.671432 -6.07568)
		(end 72.999854 -5.747258)
		(width 0.1397)
		(layer "B.Cu")
		(net "P2E_CPU_SAS_TX_DP0")
	)
	(segment
		(start 69.90334 -9.15416)
		(end 72.2122 -9.15416)
		(width 0.1397)
		(layer "B.Cu")
		(net "P2E_CPU_SAS_TX_DP0")
	)
	(segment
		(start 72.999854 -5.747258)
		(end 72.999854 -3.114548)
		(width 0.1397)
		(layer "B.Cu")
		(net "P2E_CPU_SAS_TX_DP0")
	)
	(segment
		(start 71.64832 -19.7231)
		(end 70.75424 -19.7231)
		(width 0.1397)
		(layer "B.Cu")
		(net "P2E_CPU_SAS_TX_DP0")
	)
	(segment
		(start 73.000108 -21.699474)
		(end 72.703182 -21.9964)
		(width 0.1397)
		(layer "B.Cu")
		(net "P2E_CPU_SAS_TX_DP0")
	)
	(segment
		(start 72.703182 -21.9964)
		(end 72.426322 -21.9964)
		(width 0.1397)
		(layer "B.Cu")
		(net "P2E_CPU_SAS_TX_DP0")
	)
	(segment
		(start 70.47103 -15.293848)
		(end 70.47103 -10.30859)
		(width 0.1397)
		(layer "B.Cu")
		(net "P2E_CPU_SAS_TX_DP0")
	)
	(segment
		(start 72.671432 -8.694928)
		(end 72.671432 -6.07568)
		(width 0.1397)
		(layer "B.Cu")
		(net "P2E_CPU_SAS_TX_DP0")
	)
	(segment
		(start 70.47103 -10.30859)
		(end 69.74078 -9.57834)
		(width 0.1397)
		(layer "B.Cu")
		(net "P2E_CPU_SAS_TX_DP0")
	)
	(segment
		(start 72.157082 -20.231862)
		(end 71.64832 -19.7231)
		(width 0.1397)
		(layer "B.Cu")
		(net "P2E_CPU_SAS_TX_DP0")
	)
	(segment
		(start 70.75424 -19.7231)
		(end 70.1802 -19.14906)
		(width 0.1397)
		(layer "B.Cu")
		(net "P2E_CPU_SAS_TX_DP0")
	)
	(segment
		(start 71.179182 -17.210278)
		(end 71.179182 -16.002)
		(width 0.1397)
		(layer "B.Cu")
		(net "P2E_CPU_SAS_TX_DP0")
	)
	(segment
		(start 72.2122 -9.15416)
		(end 72.671432 -8.694928)
		(width 0.1397)
		(layer "B.Cu")
		(net "P2E_CPU_SAS_TX_DP0")
	)
	(segment
		(start 72.157082 -21.72716)
		(end 72.157082 -20.231862)
		(width 0.1397)
		(layer "B.Cu")
		(net "P2E_CPU_SAS_TX_DP0")
	)
	(segment
		(start 73.000108 -21.149564)
		(end 73.000108 -21.699474)
		(width 0.1397)
		(layer "B.Cu")
		(net "P2E_CPU_SAS_TX_DP0")
	)
	(segment
		(start 71.179182 -16.002)
		(end 70.47103 -15.293848)
		(width 0.1397)
		(layer "B.Cu")
		(net "P2E_CPU_SAS_TX_DP0")
	)
	(segment
		(start 69.74078 -9.57834)
		(end 69.74078 -9.31672)
		(width 0.1397)
		(layer "B.Cu")
		(net "P2E_CPU_SAS_TX_DP0")
	)
	(segment
		(start 73.000362 -21.149564)
		(end 73.000108 -21.149564)
		(width 0.1397)
		(layer "B.Cu")
		(net "P2E_CPU_SAS_TX_DP0")
	)
	(segment
		(start 72.426322 -21.9964)
		(end 72.157082 -21.72716)
		(width 0.1397)
		(layer "B.Cu")
		(net "P2E_CPU_SAS_TX_DP0")
	)
	(segment
		(start 70.1802 -19.14906)
		(end 70.1802 -18.20926)
		(width 0.1397)
		(layer "B.Cu")
		(net "P2E_CPU_SAS_TX_DP0")
	)
	(segment
		(start 84.000086 -3.495548)
		(end 84.000086 -6.532626)
		(width 0.10795)
		(layer "F.Cu")
		(net "SLOT_ID1")
	)
	(segment
		(start 84.000086 -6.532626)
		(end 84.368132 -6.900672)
		(width 0.10795)
		(layer "F.Cu")
		(net "SLOT_ID1")
	)
	(segment
		(start 83.999832 -16.6497)
		(end 83.999832 -16.649954)
		(width 0.10795)
		(layer "F.Cu")
		(net "SLOT_ID1")
	)
	(segment
		(start 84.368132 -16.2814)
		(end 83.999832 -16.6497)
		(width 0.10795)
		(layer "F.Cu")
		(net "SLOT_ID1")
	)
	(segment
		(start 84.368132 -6.900672)
		(end 84.368132 -16.2814)
		(width 0.10795)
		(layer "F.Cu")
		(net "SLOT_ID1")
	)
	(segment
		(start 50.000662 -16.6497)
		(end 50.300382 -16.34998)
		(width 0.127)
		(layer "F.Cu")
		(net "PCIE_RSVD_A38")
	)
	(segment
		(start 50.300382 -7.1628)
		(end 49.9999 -6.862318)
		(width 0.127)
		(layer "F.Cu")
		(net "PCIE_RSVD_A38")
	)
	(segment
		(start 50.300382 -16.34998)
		(end 50.300382 -7.1628)
		(width 0.127)
		(layer "F.Cu")
		(net "PCIE_RSVD_A38")
	)
	(segment
		(start 49.9999 -6.862318)
		(end 49.9999 -3.495548)
		(width 0.127)
		(layer "F.Cu")
		(net "PCIE_RSVD_A38")
	)
	(segment
		(start 50.000662 -16.649954)
		(end 50.000662 -16.6497)
		(width 0.127)
		(layer "F.Cu")
		(net "PCIE_RSVD_A38")
	)
	(segment
		(start 89.000076 -7.618476)
		(end 89.000584 -7.618984)
		(width 0.10795)
		(layer "F.Cu")
		(net "BOARD_PRSNT#")
	)
	(segment
		(start 88.5571 -9.39038)
		(end 88.5571 -15.94104)
		(width 0.10795)
		(layer "F.Cu")
		(net "BOARD_PRSNT#")
	)
	(segment
		(start 89.000584 -8.946896)
		(end 88.5571 -9.39038)
		(width 0.10795)
		(layer "F.Cu")
		(net "BOARD_PRSNT#")
	)
	(segment
		(start 89.000584 -7.618984)
		(end 89.000584 -8.946896)
		(width 0.10795)
		(layer "F.Cu")
		(net "BOARD_PRSNT#")
	)
	(segment
		(start 89.000076 -3.990848)
		(end 89.000076 -7.618476)
		(width 0.10795)
		(layer "F.Cu")
		(net "BOARD_PRSNT#")
	)
	(segment
		(start 88.5571 -15.94104)
		(end 88.999822 -16.383762)
		(width 0.10795)
		(layer "F.Cu")
		(net "BOARD_PRSNT#")
	)
	(segment
		(start 88.999822 -16.383762)
		(end 88.999822 -18.650204)
		(width 0.10795)
		(layer "F.Cu")
		(net "BOARD_PRSNT#")
	)
	(segment
		(start 84.133182 -9.6774)
		(end 84.133182 -15.4432)
		(width 0.10795)
		(layer "F.Cu")
		(net "CPU_TXD")
	)
	(segment
		(start 83.000088 -16.576294)
		(end 83.000088 -18.650204)
		(width 0.10795)
		(layer "F.Cu")
		(net "CPU_TXD")
	)
	(segment
		(start 83.000088 -18.650204)
		(end 83.000342 -18.650204)
		(width 0.10795)
		(layer "F.Cu")
		(net "CPU_TXD")
	)
	(segment
		(start 84.133182 -15.4432)
		(end 83.000088 -16.576294)
		(width 0.10795)
		(layer "F.Cu")
		(net "CPU_TXD")
	)
	(segment
		(start 83.000088 -3.495548)
		(end 83.000088 -8.544306)
		(width 0.10795)
		(layer "F.Cu")
		(net "CPU_TXD")
	)
	(segment
		(start 83.000088 -8.544306)
		(end 84.133182 -9.6774)
		(width 0.10795)
		(layer "F.Cu")
		(net "CPU_TXD")
	)
	(segment
		(start 47.999904 -6.183122)
		(end 47.999904 -3.114548)
		(width 0.127)
		(layer "B.Cu")
		(net "PCIE_RSVD_B40")
	)
	(segment
		(start 48.649382 -6.8326)
		(end 47.999904 -6.183122)
		(width 0.127)
		(layer "B.Cu")
		(net "PCIE_RSVD_B40")
	)
	(segment
		(start 48.000158 -23.149814)
		(end 47.892462 -23.042118)
		(width 0.127)
		(layer "B.Cu")
		(net "PCIE_RSVD_B40")
	)
	(segment
		(start 48.832262 -17.025112)
		(end 48.832262 -15.237968)
		(width 0.127)
		(layer "B.Cu")
		(net "PCIE_RSVD_B40")
	)
	(segment
		(start 47.892462 -23.042118)
		(end 47.892462 -17.964912)
		(width 0.127)
		(layer "B.Cu")
		(net "PCIE_RSVD_B40")
	)
	(segment
		(start 48.000412 -23.149814)
		(end 48.000158 -23.149814)
		(width 0.127)
		(layer "B.Cu")
		(net "PCIE_RSVD_B40")
	)
	(segment
		(start 48.832262 -15.237968)
		(end 48.649382 -15.055088)
		(width 0.127)
		(layer "B.Cu")
		(net "PCIE_RSVD_B40")
	)
	(segment
		(start 48.649382 -15.055088)
		(end 48.649382 -6.8326)
		(width 0.127)
		(layer "B.Cu")
		(net "PCIE_RSVD_B40")
	)
	(segment
		(start 47.892462 -17.964912)
		(end 48.832262 -17.025112)
		(width 0.127)
		(layer "B.Cu")
		(net "PCIE_RSVD_B40")
	)
	(segment
		(start 48.999902 -21.149564)
		(end 48.999648 -21.149564)
		(width 0.10795)
		(layer "B.Cu")
		(net "PCIE1_RESET#")
	)
	(segment
		(start 48.242982 -20.392898)
		(end 48.242982 -18.1102)
		(width 0.10795)
		(layer "B.Cu")
		(net "PCIE1_RESET#")
	)
	(segment
		(start 48.999902 -14.9098)
		(end 48.999902 -3.114548)
		(width 0.10795)
		(layer "B.Cu")
		(net "PCIE1_RESET#")
	)
	(segment
		(start 48.242982 -18.1102)
		(end 49.182782 -17.1704)
		(width 0.10795)
		(layer "B.Cu")
		(net "PCIE1_RESET#")
	)
	(segment
		(start 49.182782 -15.09268)
		(end 48.999902 -14.9098)
		(width 0.10795)
		(layer "B.Cu")
		(net "PCIE1_RESET#")
	)
	(segment
		(start 48.999648 -21.149564)
		(end 48.242982 -20.392898)
		(width 0.10795)
		(layer "B.Cu")
		(net "PCIE1_RESET#")
	)
	(segment
		(start 49.182782 -17.1704)
		(end 49.182782 -15.09268)
		(width 0.10795)
		(layer "B.Cu")
		(net "PCIE1_RESET#")
	)
	(segment
		(start 80.328516 -6.07568)
		(end 80.000094 -5.747258)
		(width 0.1397)
		(layer "B.Cu")
		(net "USB_P1_DN")
	)
	(segment
		(start 78.326742 -9.3345)
		(end 79.309722 -9.3345)
		(width 0.1397)
		(layer "B.Cu")
		(net "USB_P1_DN")
	)
	(segment
		(start 77.211682 -10.44956)
		(end 78.326742 -9.3345)
		(width 0.1397)
		(layer "B.Cu")
		(net "USB_P1_DN")
	)
	(segment
		(start 77.211682 -15.66164)
		(end 77.211682 -10.44956)
		(width 0.1397)
		(layer "B.Cu")
		(net "USB_P1_DN")
	)
	(segment
		(start 79.309722 -9.3345)
		(end 80.328516 -8.315706)
		(width 0.1397)
		(layer "B.Cu")
		(net "USB_P1_DN")
	)
	(segment
		(start 79.840582 -18.29054)
		(end 77.211682 -15.66164)
		(width 0.1397)
		(layer "B.Cu")
		(net "USB_P1_DN")
	)
	(segment
		(start 79.840582 -21.7932)
		(end 79.840582 -18.29054)
		(width 0.1397)
		(layer "B.Cu")
		(net "USB_P1_DN")
	)
	(segment
		(start 80.000602 -23.14956)
		(end 80.282542 -22.86762)
		(width 0.1397)
		(layer "B.Cu")
		(net "USB_P1_DN")
	)
	(segment
		(start 80.282542 -22.23516)
		(end 79.840582 -21.7932)
		(width 0.1397)
		(layer "B.Cu")
		(net "USB_P1_DN")
	)
	(segment
		(start 80.000602 -23.149814)
		(end 80.000602 -23.14956)
		(width 0.1397)
		(layer "B.Cu")
		(net "USB_P1_DN")
	)
	(segment
		(start 80.282542 -22.86762)
		(end 80.282542 -22.23516)
		(width 0.1397)
		(layer "B.Cu")
		(net "USB_P1_DN")
	)
	(segment
		(start 80.000094 -5.747258)
		(end 80.000094 -3.114548)
		(width 0.1397)
		(layer "B.Cu")
		(net "USB_P1_DN")
	)
	(segment
		(start 80.328516 -8.315706)
		(end 80.328516 -6.07568)
		(width 0.1397)
		(layer "B.Cu")
		(net "USB_P1_DN")
	)
	(segment
		(start 80.183482 -21.65096)
		(end 80.183482 -18.1483)
		(width 0.1397)
		(layer "B.Cu")
		(net "USB_P1_DP")
	)
	(segment
		(start 80.589882 -22.05736)
		(end 80.183482 -21.65096)
		(width 0.1397)
		(layer "B.Cu")
		(net "USB_P1_DP")
	)
	(segment
		(start 77.554582 -10.5918)
		(end 78.468982 -9.6774)
		(width 0.1397)
		(layer "B.Cu")
		(net "USB_P1_DP")
	)
	(segment
		(start 80.183482 -18.1483)
		(end 77.554582 -15.5194)
		(width 0.1397)
		(layer "B.Cu")
		(net "USB_P1_DP")
	)
	(segment
		(start 80.589882 -22.0599)
		(end 80.589882 -22.05736)
		(width 0.1397)
		(layer "B.Cu")
		(net "USB_P1_DP")
	)
	(segment
		(start 80.999838 -21.853144)
		(end 80.790288 -22.062694)
		(width 0.1397)
		(layer "B.Cu")
		(net "USB_P1_DP")
	)
	(segment
		(start 77.554582 -15.5194)
		(end 77.554582 -10.5918)
		(width 0.1397)
		(layer "B.Cu")
		(net "USB_P1_DP")
	)
	(segment
		(start 80.671416 -8.457946)
		(end 80.671416 -6.07568)
		(width 0.1397)
		(layer "B.Cu")
		(net "USB_P1_DP")
	)
	(segment
		(start 80.671416 -6.07568)
		(end 81.000092 -5.747004)
		(width 0.1397)
		(layer "B.Cu")
		(net "USB_P1_DP")
	)
	(segment
		(start 80.790288 -22.062694)
		(end 80.592676 -22.062694)
		(width 0.1397)
		(layer "B.Cu")
		(net "USB_P1_DP")
	)
	(segment
		(start 81.000092 -21.149564)
		(end 80.999838 -21.149564)
		(width 0.1397)
		(layer "B.Cu")
		(net "USB_P1_DP")
	)
	(segment
		(start 78.468982 -9.6774)
		(end 79.451962 -9.6774)
		(width 0.1397)
		(layer "B.Cu")
		(net "USB_P1_DP")
	)
	(segment
		(start 79.451962 -9.6774)
		(end 80.671416 -8.457946)
		(width 0.1397)
		(layer "B.Cu")
		(net "USB_P1_DP")
	)
	(segment
		(start 80.592676 -22.062694)
		(end 80.589882 -22.0599)
		(width 0.1397)
		(layer "B.Cu")
		(net "USB_P1_DP")
	)
	(segment
		(start 81.000092 -5.747004)
		(end 81.000092 -3.114548)
		(width 0.1397)
		(layer "B.Cu")
		(net "USB_P1_DP")
	)
	(segment
		(start 80.999838 -21.149564)
		(end 80.999838 -21.853144)
		(width 0.1397)
		(layer "B.Cu")
		(net "USB_P1_DP")
	)
	(segment
		(start 52.328572 -14.3764)
		(end 52.328572 -6.07568)
		(width 0.1397)
		(layer "B.Cu")
		(net "CLK_100M_CLKBUFF_ENET_DN")
	)
	(segment
		(start 52.827682 -17.0561)
		(end 52.827682 -14.87551)
		(width 0.1397)
		(layer "B.Cu")
		(net "CLK_100M_CLKBUFF_ENET_DN")
	)
	(segment
		(start 51.875182 -21.8948)
		(end 51.875182 -18.0086)
		(width 0.1397)
		(layer "B.Cu")
		(net "CLK_100M_CLKBUFF_ENET_DN")
	)
	(segment
		(start 52.827682 -14.87551)
		(end 52.328572 -14.3764)
		(width 0.1397)
		(layer "B.Cu")
		(net "CLK_100M_CLKBUFF_ENET_DN")
	)
	(segment
		(start 52.328572 -6.07568)
		(end 51.999896 -5.747004)
		(width 0.1397)
		(layer "B.Cu")
		(net "CLK_100M_CLKBUFF_ENET_DN")
	)
	(segment
		(start 51.875182 -18.0086)
		(end 52.827682 -17.0561)
		(width 0.1397)
		(layer "B.Cu")
		(net "CLK_100M_CLKBUFF_ENET_DN")
	)
	(segment
		(start 52.179982 -22.969474)
		(end 52.179982 -22.1996)
		(width 0.1397)
		(layer "B.Cu")
		(net "CLK_100M_CLKBUFF_ENET_DN")
	)
	(segment
		(start 51.999642 -23.149814)
		(end 52.179982 -22.969474)
		(width 0.1397)
		(layer "B.Cu")
		(net "CLK_100M_CLKBUFF_ENET_DN")
	)
	(segment
		(start 51.999896 -5.747004)
		(end 51.999896 -3.114548)
		(width 0.1397)
		(layer "B.Cu")
		(net "CLK_100M_CLKBUFF_ENET_DN")
	)
	(segment
		(start 52.179982 -22.1996)
		(end 51.875182 -21.8948)
		(width 0.1397)
		(layer "B.Cu")
		(net "CLK_100M_CLKBUFF_ENET_DN")
	)
	(segment
		(start 84.000086 -5.886704)
		(end 84.000086 -3.114548)
		(width 0.10795)
		(layer "B.Cu")
		(net "BMC_I2C_DATA")
	)
	(segment
		(start 83.272376 -17.249394)
		(end 83.272376 -15.973806)
		(width 0.10795)
		(layer "B.Cu")
		(net "BMC_I2C_DATA")
	)
	(segment
		(start 83.999832 -23.149814)
		(end 83.999832 -17.97685)
		(width 0.10795)
		(layer "B.Cu")
		(net "BMC_I2C_DATA")
	)
	(segment
		(start 83.272376 -15.973806)
		(end 84.212684 -15.033498)
		(width 0.10795)
		(layer "B.Cu")
		(net "BMC_I2C_DATA")
	)
	(segment
		(start 84.212684 -15.033498)
		(end 84.212684 -6.099302)
		(width 0.10795)
		(layer "B.Cu")
		(net "BMC_I2C_DATA")
	)
	(segment
		(start 83.999832 -17.97685)
		(end 83.272376 -17.249394)
		(width 0.10795)
		(layer "B.Cu")
		(net "BMC_I2C_DATA")
	)
	(segment
		(start 84.212684 -6.099302)
		(end 84.000086 -5.886704)
		(width 0.10795)
		(layer "B.Cu")
		(net "BMC_I2C_DATA")
	)
	(segment
		(start 74.671428 -7.000494)
		(end 74.671428 -6.07568)
		(width 0.1397)
		(layer "F.Cu")
		(net "CLK_100M_PCIE_SAS_C_P")
	)
	(segment
		(start 75.000612 -18.650204)
		(end 75.000358 -18.650204)
		(width 0.1397)
		(layer "F.Cu")
		(net "CLK_100M_PCIE_SAS_C_P")
	)
	(segment
		(start 74.99985 -5.747258)
		(end 74.99985 -3.495548)
		(width 0.1397)
		(layer "F.Cu")
		(net "CLK_100M_PCIE_SAS_C_P")
	)
	(segment
		(start 74.201782 -7.47014)
		(end 74.671428 -7.000494)
		(width 0.1397)
		(layer "F.Cu")
		(net "CLK_100M_PCIE_SAS_C_P")
	)
	(segment
		(start 75.000358 -18.060924)
		(end 75.319382 -17.7419)
		(width 0.1397)
		(layer "F.Cu")
		(net "CLK_100M_PCIE_SAS_C_P")
	)
	(segment
		(start 77.110082 -17.33042)
		(end 77.110082 -10.0203)
		(width 0.1397)
		(layer "F.Cu")
		(net "CLK_100M_PCIE_SAS_C_P")
	)
	(segment
		(start 76.470002 -9.38022)
		(end 74.887582 -9.38022)
		(width 0.1397)
		(layer "F.Cu")
		(net "CLK_100M_PCIE_SAS_C_P")
	)
	(segment
		(start 75.000358 -18.650204)
		(end 75.000358 -18.060924)
		(width 0.1397)
		(layer "F.Cu")
		(net "CLK_100M_PCIE_SAS_C_P")
	)
	(segment
		(start 74.671428 -6.07568)
		(end 74.99985 -5.747258)
		(width 0.1397)
		(layer "F.Cu")
		(net "CLK_100M_PCIE_SAS_C_P")
	)
	(segment
		(start 75.319382 -17.7419)
		(end 76.698602 -17.7419)
		(width 0.1397)
		(layer "F.Cu")
		(net "CLK_100M_PCIE_SAS_C_P")
	)
	(segment
		(start 77.110082 -10.0203)
		(end 76.470002 -9.38022)
		(width 0.1397)
		(layer "F.Cu")
		(net "CLK_100M_PCIE_SAS_C_P")
	)
	(segment
		(start 76.698602 -17.7419)
		(end 77.110082 -17.33042)
		(width 0.1397)
		(layer "F.Cu")
		(net "CLK_100M_PCIE_SAS_C_P")
	)
	(segment
		(start 74.887582 -9.38022)
		(end 74.201782 -8.69442)
		(width 0.1397)
		(layer "F.Cu")
		(net "CLK_100M_PCIE_SAS_C_P")
	)
	(segment
		(start 74.201782 -8.69442)
		(end 74.201782 -7.47014)
		(width 0.1397)
		(layer "F.Cu")
		(net "CLK_100M_PCIE_SAS_C_P")
	)
	(segment
		(start 76.327762 -9.72312)
		(end 74.745342 -9.72312)
		(width 0.1397)
		(layer "F.Cu")
		(net "CLK_100M_PCIE_SAS_C_N")
	)
	(segment
		(start 74.328528 -6.07568)
		(end 73.999852 -5.747004)
		(width 0.1397)
		(layer "F.Cu")
		(net "CLK_100M_PCIE_SAS_C_N")
	)
	(segment
		(start 76.767182 -17.18818)
		(end 76.767182 -10.16254)
		(width 0.1397)
		(layer "F.Cu")
		(net "CLK_100M_PCIE_SAS_C_N")
	)
	(segment
		(start 73.858882 -8.83666)
		(end 73.858882 -7.3279)
		(width 0.1397)
		(layer "F.Cu")
		(net "CLK_100M_PCIE_SAS_C_N")
	)
	(segment
		(start 73.858882 -7.3279)
		(end 74.328528 -6.858254)
		(width 0.1397)
		(layer "F.Cu")
		(net "CLK_100M_PCIE_SAS_C_N")
	)
	(segment
		(start 76.767182 -10.16254)
		(end 76.327762 -9.72312)
		(width 0.1397)
		(layer "F.Cu")
		(net "CLK_100M_PCIE_SAS_C_N")
	)
	(segment
		(start 73.999598 -16.649954)
		(end 74.748644 -17.399)
		(width 0.1397)
		(layer "F.Cu")
		(net "CLK_100M_PCIE_SAS_C_N")
	)
	(segment
		(start 74.328528 -6.858254)
		(end 74.328528 -6.07568)
		(width 0.1397)
		(layer "F.Cu")
		(net "CLK_100M_PCIE_SAS_C_N")
	)
	(segment
		(start 74.745342 -9.72312)
		(end 73.858882 -8.83666)
		(width 0.1397)
		(layer "F.Cu")
		(net "CLK_100M_PCIE_SAS_C_N")
	)
	(segment
		(start 76.556362 -17.399)
		(end 76.767182 -17.18818)
		(width 0.1397)
		(layer "F.Cu")
		(net "CLK_100M_PCIE_SAS_C_N")
	)
	(segment
		(start 73.999852 -5.747004)
		(end 73.999852 -3.495548)
		(width 0.1397)
		(layer "F.Cu")
		(net "CLK_100M_PCIE_SAS_C_N")
	)
	(segment
		(start 73.999852 -16.649954)
		(end 73.999598 -16.649954)
		(width 0.1397)
		(layer "F.Cu")
		(net "CLK_100M_PCIE_SAS_C_N")
	)
	(segment
		(start 74.748644 -17.399)
		(end 76.556362 -17.399)
		(width 0.1397)
		(layer "F.Cu")
		(net "CLK_100M_PCIE_SAS_C_N")
	)
	(segment
		(start 85.000084 -3.495548)
		(end 85.000084 -6.554216)
		(width 0.10795)
		(layer "F.Cu")
		(net "SLOT_ID0")
	)
	(segment
		(start 84.76488 -18.414492)
		(end 85.000592 -18.650204)
		(width 0.10795)
		(layer "F.Cu")
		(net "SLOT_ID0")
	)
	(segment
		(start 84.60486 -6.94944)
		(end 84.60486 -16.08328)
		(width 0.10795)
		(layer "F.Cu")
		(net "SLOT_ID0")
	)
	(segment
		(start 84.60486 -16.08328)
		(end 84.76488 -16.2433)
		(width 0.10795)
		(layer "F.Cu")
		(net "SLOT_ID0")
	)
	(segment
		(start 85.000084 -6.554216)
		(end 84.60486 -6.94944)
		(width 0.10795)
		(layer "F.Cu")
		(net "SLOT_ID0")
	)
	(segment
		(start 84.76488 -16.2433)
		(end 84.76488 -18.414492)
		(width 0.10795)
		(layer "F.Cu")
		(net "SLOT_ID0")
	)
	(segment
		(start 81.999582 -18.292318)
		(end 82.888582 -17.403318)
		(width 0.10795)
		(layer "B.Cu")
		(net "PMU_PWRBTN#")
	)
	(segment
		(start 81.999582 -23.149814)
		(end 81.999582 -18.292318)
		(width 0.10795)
		(layer "B.Cu")
		(net "PMU_PWRBTN#")
	)
	(segment
		(start 83.388962 -8.47598)
		(end 82.00009 -7.087108)
		(width 0.10795)
		(layer "B.Cu")
		(net "PMU_PWRBTN#")
	)
	(segment
		(start 83.388962 -15.05966)
		(end 83.388962 -8.47598)
		(width 0.10795)
		(layer "B.Cu")
		(net "PMU_PWRBTN#")
	)
	(segment
		(start 82.00009 -7.087108)
		(end 82.00009 -3.114548)
		(width 0.10795)
		(layer "B.Cu")
		(net "PMU_PWRBTN#")
	)
	(segment
		(start 82.888582 -17.403318)
		(end 82.888582 -15.56004)
		(width 0.10795)
		(layer "B.Cu")
		(net "PMU_PWRBTN#")
	)
	(segment
		(start 82.888582 -15.56004)
		(end 83.388962 -15.05966)
		(width 0.10795)
		(layer "B.Cu")
		(net "PMU_PWRBTN#")
	)
	(segment
		(start 86.999572 -18.650204)
		(end 87.90178 -18.650204)
		(width 0.508)
		(layer "F.Cu")
		(net "P12V")
	)
	(segment
		(start 6.999732 -18.650204)
		(end 6.999732 -19.552412)
		(width 0.508)
		(layer "F.Cu")
		(net "P12V")
	)
	(segment
		(start 86.999572 -17.747996)
		(end 86.999572 -18.650204)
		(width 0.508)
		(layer "F.Cu")
		(net "P12V")
	)
	(segment
		(start 88.000078 -6.152896)
		(end 88.000078 -3.495548)
		(width 0.635)
		(layer "F.Cu")
		(net "P12V")
	)
	(segment
		(start 86.999572 -20.247356)
		(end 86.999572 -21.149564)
		(width 0.508)
		(layer "F.Cu")
		(net "P12V")
	)
	(segment
		(start 87.098124 -16.649954)
		(end 88.000332 -16.649954)
		(width 0.508)
		(layer "F.Cu")
		(net "P12V")
	)
	(segment
		(start 87.00008 -3.495548)
		(end 87.00008 -6.581902)
		(width 0.635)
		(layer "F.Cu")
		(net "P12V")
	)
	(segment
		(start 5.098034 -16.649954)
		(end 6.000242 -16.649954)
		(width 0.508)
		(layer "F.Cu")
		(net "P12V")
	)
	(segment
		(start 6.999986 -3.495548)
		(end 6.999986 -6.978396)
		(width 0.635)
		(layer "F.Cu")
		(net "P12V")
	)
	(segment
		(start 6.000242 -16.649954)
		(end 6.90245 -16.649954)
		(width 0.508)
		(layer "F.Cu")
		(net "P12V")
	)
	(segment
		(start 86.097364 -21.149564)
		(end 86.999572 -21.149564)
		(width 0.508)
		(layer "F.Cu")
		(net "P12V")
	)
	(segment
		(start 87.098124 -23.149814)
		(end 88.000332 -23.149814)
		(width 0.508)
		(layer "F.Cu")
		(net "P12V")
	)
	(segment
		(start 6.097524 -18.650204)
		(end 6.999732 -18.650204)
		(width 0.508)
		(layer "F.Cu")
		(net "P12V")
	)
	(segment
		(start 6.000242 -15.747746)
		(end 6.000242 -16.649954)
		(width 0.508)
		(layer "F.Cu")
		(net "P12V")
	)
	(segment
		(start 88.000332 -22.247606)
		(end 88.000332 -23.149814)
		(width 0.508)
		(layer "F.Cu")
		(net "P12V")
	)
	(segment
		(start 6.999732 -17.747996)
		(end 6.999732 -18.650204)
		(width 0.508)
		(layer "F.Cu")
		(net "P12V")
	)
	(segment
		(start 88.000332 -23.149814)
		(end 88.000332 -24.052022)
		(width 0.508)
		(layer "F.Cu")
		(net "P12V")
	)
	(segment
		(start 86.999572 -21.149564)
		(end 87.90178 -21.149564)
		(width 0.508)
		(layer "F.Cu")
		(net "P12V")
	)
	(segment
		(start 88.999822 -20.247356)
		(end 88.999822 -21.149564)
		(width 0.508)
		(layer "F.Cu")
		(net "P12V")
	)
	(segment
		(start 6.999732 -18.650204)
		(end 7.90194 -18.650204)
		(width 0.508)
		(layer "F.Cu")
		(net "P12V")
	)
	(segment
		(start 86.999572 -21.149564)
		(end 86.999572 -22.051772)
		(width 0.508)
		(layer "F.Cu")
		(net "P12V")
	)
	(segment
		(start 86.097364 -18.650204)
		(end 86.999572 -18.650204)
		(width 0.508)
		(layer "F.Cu")
		(net "P12V")
	)
	(segment
		(start 5.999988 -6.804406)
		(end 5.999988 -3.495548)
		(width 0.635)
		(layer "F.Cu")
		(net "P12V")
	)
	(segment
		(start 88.097614 -21.149564)
		(end 88.999822 -21.149564)
		(width 0.508)
		(layer "F.Cu")
		(net "P12V")
	)
	(segment
		(start 88.999822 -21.149564)
		(end 89.90203 -21.149564)
		(width 0.508)
		(layer "F.Cu")
		(net "P12V")
	)
	(segment
		(start 86.999572 -18.650204)
		(end 86.999572 -19.552412)
		(width 0.508)
		(layer "F.Cu")
		(net "P12V")
	)
	(segment
		(start 88.999822 -21.149564)
		(end 88.999822 -22.051772)
		(width 0.508)
		(layer "F.Cu")
		(net "P12V")
	)
	(segment
		(start 88.000332 -16.649954)
		(end 88.000332 -17.552162)
		(width 0.508)
		(layer "F.Cu")
		(net "P12V")
	)
	(segment
		(start 6.000242 -16.649954)
		(end 6.000242 -17.552162)
		(width 0.508)
		(layer "F.Cu")
		(net "P12V")
	)
	(segment
		(start 88.000332 -23.149814)
		(end 88.90254 -23.149814)
		(width 0.508)
		(layer "F.Cu")
		(net "P12V")
	)
	(via
		(at 4.326382 -13.5763)
		(size 0.7112)
		(drill 0.4064)
		(layers "F.Cu" "B.Cu")
		(net "P12V")
	)
	(via
		(at 90.36558 -19.98472)
		(size 0.7112)
		(drill 0.4064)
		(layers "F.Cu" "B.Cu")
		(net "P12V")
	)
	(via
		(at 86.38032 -12.18184)
		(size 0.7112)
		(drill 0.4064)
		(layers "F.Cu" "B.Cu")
		(net "P12V")
	)
	(via
		(at 6.536182 -13.5763)
		(size 0.7112)
		(drill 0.4064)
		(layers "F.Cu" "B.Cu")
		(net "P12V")
	)
	(via
		(at 87.46744 -11.09218)
		(size 0.7112)
		(drill 0.4064)
		(layers "F.Cu" "B.Cu")
		(net "P12V")
	)
	(via
		(at 3.894582 -15.9258)
		(size 0.7112)
		(drill 0.4064)
		(layers "F.Cu" "B.Cu")
		(net "P12V")
	)
	(via
		(at 3.970782 -17.653)
		(size 0.7112)
		(drill 0.4064)
		(layers "F.Cu" "B.Cu")
		(net "P12V")
	)
	(via
		(at 7.831582 -14.9098)
		(size 0.7112)
		(drill 0.4064)
		(layers "F.Cu" "B.Cu")
		(net "P12V")
	)
	(via
		(at 5.469382 -15.0114)
		(size 0.7112)
		(drill 0.4064)
		(layers "F.Cu" "B.Cu")
		(net "P12V")
	)
	(via
		(at 86.36254 -14.87678)
		(size 0.7112)
		(drill 0.4064)
		(layers "F.Cu" "B.Cu")
		(net "P12V")
	)
	(via
		(at 7.79272 -10.8458)
		(size 0.7112)
		(drill 0.4064)
		(layers "F.Cu" "B.Cu")
		(net "P12V")
	)
	(via
		(at 87.126826 -8.256016)
		(size 0.7112)
		(drill 0.4064)
		(layers "F.Cu" "B.Cu")
		(net "P12V")
	)
	(via
		(at 90.0811 -22.83206)
		(size 0.7112)
		(drill 0.4064)
		(layers "F.Cu" "B.Cu")
		(net "P12V")
	)
	(via
		(at 90.7669 -18.32864)
		(size 0.7112)
		(drill 0.4064)
		(layers "F.Cu" "B.Cu")
		(net "P12V")
	)
	(via
		(at 87.2998 -13.68806)
		(size 0.7112)
		(drill 0.4064)
		(layers "F.Cu" "B.Cu")
		(net "P12V")
	)
	(via
		(at 88.276176 -8.2296)
		(size 0.7112)
		(drill 0.4064)
		(layers "F.Cu" "B.Cu")
		(net "P12V")
	)
	(via
		(at 6.02488 -9.62152)
		(size 0.7112)
		(drill 0.4064)
		(layers "F.Cu" "B.Cu")
		(net "P12V")
	)
	(segment
		(start 6.999732 -18.650204)
		(end 6.999732 -19.552412)
		(width 0.508)
		(layer "B.Cu")
		(net "P12V")
	)
	(segment
		(start 88.000332 -22.247606)
		(end 88.000332 -23.149814)
		(width 0.508)
		(layer "B.Cu")
		(net "P12V")
	)
	(segment
		(start 88.000332 -16.649954)
		(end 88.000332 -17.552162)
		(width 0.508)
		(layer "B.Cu")
		(net "P12V")
	)
	(segment
		(start 89.000076 -7.5057)
		(end 89.000076 -3.114548)
		(width 0.635)
		(layer "B.Cu")
		(net "P12V")
	)
	(segment
		(start 88.000332 -15.747746)
		(end 88.000332 -16.649954)
		(width 0.508)
		(layer "B.Cu")
		(net "P12V")
	)
	(segment
		(start 6.097524 -18.650204)
		(end 6.999732 -18.650204)
		(width 0.508)
		(layer "B.Cu")
		(net "P12V")
	)
	(segment
		(start 88.000332 -23.149814)
		(end 88.90254 -23.149814)
		(width 0.508)
		(layer "B.Cu")
		(net "P12V")
	)
	(segment
		(start 6.999732 -17.747996)
		(end 6.999732 -18.650204)
		(width 0.508)
		(layer "B.Cu")
		(net "P12V")
	)
	(segment
		(start 86.999572 -20.247356)
		(end 86.999572 -21.149564)
		(width 0.508)
		(layer "B.Cu")
		(net "P12V")
	)
	(segment
		(start 86.999572 -21.149564)
		(end 86.999572 -22.051772)
		(width 0.508)
		(layer "B.Cu")
		(net "P12V")
	)
	(segment
		(start 87.098124 -16.649954)
		(end 88.000332 -16.649954)
		(width 0.508)
		(layer "B.Cu")
		(net "P12V")
	)
	(segment
		(start 6.000242 -16.649954)
		(end 6.90245 -16.649954)
		(width 0.508)
		(layer "B.Cu")
		(net "P12V")
	)
	(segment
		(start 6.000242 -15.747746)
		(end 6.000242 -16.649954)
		(width 0.508)
		(layer "B.Cu")
		(net "P12V")
	)
	(segment
		(start 6.000242 -16.649954)
		(end 6.000242 -17.552162)
		(width 0.508)
		(layer "B.Cu")
		(net "P12V")
	)
	(segment
		(start 5.098034 -16.649954)
		(end 6.000242 -16.649954)
		(width 0.508)
		(layer "B.Cu")
		(net "P12V")
	)
	(segment
		(start 88.276176 -8.2296)
		(end 89.000076 -7.5057)
		(width 0.635)
		(layer "B.Cu")
		(net "P12V")
	)
	(segment
		(start 88.999822 -21.149564)
		(end 89.90203 -21.149564)
		(width 0.508)
		(layer "B.Cu")
		(net "P12V")
	)
	(segment
		(start 86.999572 -17.747996)
		(end 86.999572 -18.650204)
		(width 0.508)
		(layer "B.Cu")
		(net "P12V")
	)
	(segment
		(start 87.00008 -3.114548)
		(end 87.00008 -7.337298)
		(width 0.635)
		(layer "B.Cu")
		(net "P12V")
	)
	(segment
		(start 86.097364 -18.650204)
		(end 86.999572 -18.650204)
		(width 0.508)
		(layer "B.Cu")
		(net "P12V")
	)
	(segment
		(start 88.999822 -20.247356)
		(end 88.999822 -21.149564)
		(width 0.508)
		(layer "B.Cu")
		(net "P12V")
	)
	(segment
		(start 87.098124 -23.149814)
		(end 88.000332 -23.149814)
		(width 0.508)
		(layer "B.Cu")
		(net "P12V")
	)
	(segment
		(start 86.097364 -21.149564)
		(end 86.999572 -21.149564)
		(width 0.508)
		(layer "B.Cu")
		(net "P12V")
	)
	(segment
		(start 86.999572 -18.650204)
		(end 87.90178 -18.650204)
		(width 0.508)
		(layer "B.Cu")
		(net "P12V")
	)
	(segment
		(start 88.000332 -16.649954)
		(end 88.90254 -16.649954)
		(width 0.508)
		(layer "B.Cu")
		(net "P12V")
	)
	(segment
		(start 88.999822 -21.149564)
		(end 88.999822 -22.051772)
		(width 0.508)
		(layer "B.Cu")
		(net "P12V")
	)
	(segment
		(start 88.097614 -21.149564)
		(end 88.999822 -21.149564)
		(width 0.508)
		(layer "B.Cu")
		(net "P12V")
	)
	(segment
		(start 86.999572 -21.149564)
		(end 87.90178 -21.149564)
		(width 0.508)
		(layer "B.Cu")
		(net "P12V")
	)
	(segment
		(start 88.000332 -23.149814)
		(end 88.000332 -24.052022)
		(width 0.508)
		(layer "B.Cu")
		(net "P12V")
	)
	(segment
		(start 88.000078 -6.985)
		(end 88.000078 -3.114548)
		(width 0.635)
		(layer "B.Cu")
		(net "P12V")
	)
	(segment
		(start 86.999572 -18.650204)
		(end 86.999572 -19.552412)
		(width 0.508)
		(layer "B.Cu")
		(net "P12V")
	)
	(segment
		(start 84.27339 -20.422616)
		(end 85.000338 -21.149564)
		(width 0.10795)
		(layer "B.Cu")
		(net "BMC_I2C_CLK")
	)
	(segment
		(start 84.27339 -18.071592)
		(end 84.27339 -20.422616)
		(width 0.10795)
		(layer "B.Cu")
		(net "BMC_I2C_CLK")
	)
	(segment
		(start 85.000084 -3.114548)
		(end 85.000084 -17.344898)
		(width 0.10795)
		(layer "B.Cu")
		(net "BMC_I2C_CLK")
	)
	(segment
		(start 85.000084 -17.344898)
		(end 84.27339 -18.071592)
		(width 0.10795)
		(layer "B.Cu")
		(net "BMC_I2C_CLK")
	)
	(segment
		(start 85.000338 -21.149564)
		(end 85.000592 -21.149564)
		(width 0.10795)
		(layer "B.Cu")
		(net "BMC_I2C_CLK")
	)
	(segment
		(start 75.999848 -3.114548)
		(end 75.999848 -8.793734)
		(width 0.10795)
		(layer "B.Cu")
		(net "BMC_I2C_ALERT#")
	)
	(segment
		(start 75.522582 -19.156426)
		(end 75.522582 -20.6248)
		(width 0.10795)
		(layer "B.Cu")
		(net "BMC_I2C_ALERT#")
	)
	(segment
		(start 76.767182 -16.3576)
		(end 76.767182 -17.911826)
		(width 0.10795)
		(layer "B.Cu")
		(net "BMC_I2C_ALERT#")
	)
	(segment
		(start 71.712582 -15.7988)
		(end 76.208382 -15.7988)
		(width 0.10795)
		(layer "B.Cu")
		(net "BMC_I2C_ALERT#")
	)
	(segment
		(start 76.208382 -15.7988)
		(end 76.767182 -16.3576)
		(width 0.10795)
		(layer "B.Cu")
		(net "BMC_I2C_ALERT#")
	)
	(segment
		(start 75.999848 -21.102066)
		(end 75.999848 -23.149814)
		(width 0.10795)
		(layer "B.Cu")
		(net "BMC_I2C_ALERT#")
	)
	(segment
		(start 76.767182 -17.911826)
		(end 75.522582 -19.156426)
		(width 0.10795)
		(layer "B.Cu")
		(net "BMC_I2C_ALERT#")
	)
	(segment
		(start 71.595742 -9.66724)
		(end 70.975982 -10.287)
		(width 0.10795)
		(layer "B.Cu")
		(net "BMC_I2C_ALERT#")
	)
	(segment
		(start 75.999848 -23.149814)
		(end 76.000102 -23.149814)
		(width 0.10795)
		(layer "B.Cu")
		(net "BMC_I2C_ALERT#")
	)
	(segment
		(start 75.999848 -8.793734)
		(end 75.126342 -9.66724)
		(width 0.10795)
		(layer "B.Cu")
		(net "BMC_I2C_ALERT#")
	)
	(segment
		(start 70.975982 -10.287)
		(end 70.975982 -15.0622)
		(width 0.10795)
		(layer "B.Cu")
		(net "BMC_I2C_ALERT#")
	)
	(segment
		(start 70.975982 -15.0622)
		(end 71.712582 -15.7988)
		(width 0.10795)
		(layer "B.Cu")
		(net "BMC_I2C_ALERT#")
	)
	(segment
		(start 75.522582 -20.6248)
		(end 75.999848 -21.102066)
		(width 0.10795)
		(layer "B.Cu")
		(net "BMC_I2C_ALERT#")
	)
	(segment
		(start 75.126342 -9.66724)
		(end 71.595742 -9.66724)
		(width 0.10795)
		(layer "B.Cu")
		(net "BMC_I2C_ALERT#")
	)
	(segment
		(start 80.000602 -16.649954)
		(end 80.000602 -16.6497)
		(width 0.10795)
		(layer "F.Cu")
		(net "SLOT_ID3")
	)
	(segment
		(start 82.736182 -15.6718)
		(end 83.371182 -15.0368)
		(width 0.10795)
		(layer "F.Cu")
		(net "SLOT_ID3")
	)
	(segment
		(start 80.000602 -16.6497)
		(end 80.978502 -15.6718)
		(width 0.10795)
		(layer "F.Cu")
		(net "SLOT_ID3")
	)
	(segment
		(start 80.978502 -15.6718)
		(end 82.736182 -15.6718)
		(width 0.10795)
		(layer "F.Cu")
		(net "SLOT_ID3")
	)
	(segment
		(start 83.371182 -10.2616)
		(end 80.000094 -6.890512)
		(width 0.10795)
		(layer "F.Cu")
		(net "SLOT_ID3")
	)
	(segment
		(start 83.371182 -15.0368)
		(end 83.371182 -10.2616)
		(width 0.10795)
		(layer "F.Cu")
		(net "SLOT_ID3")
	)
	(segment
		(start 80.000094 -6.890512)
		(end 80.000094 -3.495548)
		(width 0.10795)
		(layer "F.Cu")
		(net "SLOT_ID3")
	)
	(segment
		(start 77.224382 -17.8308)
		(end 77.224382 -16.4084)
		(width 0.10795)
		(layer "B.Cu")
		(net "BMC_SYS_RESET#")
	)
	(segment
		(start 79.000096 -5.890514)
		(end 79.000096 -3.114548)
		(width 0.10795)
		(layer "B.Cu")
		(net "BMC_SYS_RESET#")
	)
	(segment
		(start 78.964282 -8.8138)
		(end 79.434182 -8.3439)
		(width 0.10795)
		(layer "B.Cu")
		(net "BMC_SYS_RESET#")
	)
	(segment
		(start 77.224382 -16.4084)
		(end 76.690982 -15.875)
		(width 0.10795)
		(layer "B.Cu")
		(net "BMC_SYS_RESET#")
	)
	(segment
		(start 76.792582 -21.5392)
		(end 75.801982 -20.5486)
		(width 0.10795)
		(layer "B.Cu")
		(net "BMC_SYS_RESET#")
	)
	(segment
		(start 76.690982 -15.875)
		(end 76.690982 -10.2362)
		(width 0.10795)
		(layer "B.Cu")
		(net "BMC_SYS_RESET#")
	)
	(segment
		(start 76.690982 -10.2362)
		(end 78.113382 -8.8138)
		(width 0.10795)
		(layer "B.Cu")
		(net "BMC_SYS_RESET#")
	)
	(segment
		(start 78.999588 -21.149564)
		(end 78.609952 -21.5392)
		(width 0.10795)
		(layer "B.Cu")
		(net "BMC_SYS_RESET#")
	)
	(segment
		(start 78.609952 -21.5392)
		(end 76.792582 -21.5392)
		(width 0.10795)
		(layer "B.Cu")
		(net "BMC_SYS_RESET#")
	)
	(segment
		(start 75.801982 -20.5486)
		(end 75.801982 -19.2532)
		(width 0.10795)
		(layer "B.Cu")
		(net "BMC_SYS_RESET#")
	)
	(segment
		(start 79.434182 -8.3439)
		(end 79.434182 -6.3246)
		(width 0.10795)
		(layer "B.Cu")
		(net "BMC_SYS_RESET#")
	)
	(segment
		(start 78.113382 -8.8138)
		(end 78.964282 -8.8138)
		(width 0.10795)
		(layer "B.Cu")
		(net "BMC_SYS_RESET#")
	)
	(segment
		(start 79.434182 -6.3246)
		(end 79.000096 -5.890514)
		(width 0.10795)
		(layer "B.Cu")
		(net "BMC_SYS_RESET#")
	)
	(segment
		(start 78.999842 -21.149564)
		(end 78.999588 -21.149564)
		(width 0.10795)
		(layer "B.Cu")
		(net "BMC_SYS_RESET#")
	)
	(segment
		(start 75.801982 -19.2532)
		(end 77.224382 -17.8308)
		(width 0.10795)
		(layer "B.Cu")
		(net "BMC_SYS_RESET#")
	)
	(segment
		(start 8.999982 -6.41604)
		(end 8.959342 -6.45668)
		(width 0.508)
		(layer "F.Cu")
		(net "GND")
	)
	(segment
		(start 19.99996 -7.669022)
		(end 19.617182 -8.0518)
		(width 0.508)
		(layer "F.Cu")
		(net "GND")
	)
	(segment
		(start 28.999942 -3.495548)
		(end 28.999942 -7.47776)
		(width 0.508)
		(layer "F.Cu")
		(net "GND")
	)
	(segment
		(start 86.000082 -3.495548)
		(end 86.000082 -8.1407)
		(width 0.508)
		(layer "F.Cu")
		(net "GND")
	)
	(segment
		(start 52.999894 -7.500112)
		(end 53.500782 -8.001)
		(width 0.508)
		(layer "F.Cu")
		(net "GND")
	)
	(segment
		(start 24.99995 -7.414768)
		(end 25.586182 -8.001)
		(width 0.508)
		(layer "F.Cu")
		(net "GND")
	)
	(segment
		(start 23.999952 -3.495548)
		(end 23.999952 -7.50443)
		(width 0.508)
		(layer "F.Cu")
		(net "GND")
	)
	(segment
		(start 75.999848 -3.495548)
		(end 75.999848 -7.041134)
		(width 0.508)
		(layer "F.Cu")
		(net "GND")
	)
	(segment
		(start 44.99991 -7.526528)
		(end 45.499782 -8.0264)
		(width 0.508)
		(layer "F.Cu")
		(net "GND")
	)
	(segment
		(start 20.999958 -3.495548)
		(end 20.999958 -7.580376)
		(width 0.508)
		(layer "F.Cu")
		(net "GND")
	)
	(segment
		(start 8.959342 -6.45668)
		(end 8.314182 -6.45668)
		(width 0.508)
		(layer "F.Cu")
		(net "GND")
	)
	(segment
		(start 32.999934 -7.413752)
		(end 33.612582 -8.0264)
		(width 0.508)
		(layer "F.Cu")
		(net "GND")
	)
	(segment
		(start 72.999854 -3.495548)
		(end 72.999854 -7.591552)
		(width 0.508)
		(layer "F.Cu")
		(net "GND")
	)
	(segment
		(start 51.999896 -3.495548)
		(end 51.999896 -7.393686)
		(width 0.508)
		(layer "F.Cu")
		(net "GND")
	)
	(segment
		(start 15.999968 -3.495548)
		(end 15.999968 -7.401814)
		(width 0.508)
		(layer "F.Cu")
		(net "GND")
	)
	(segment
		(start 59.99988 -3.495548)
		(end 59.99988 -7.496302)
		(width 0.508)
		(layer "F.Cu")
		(net "GND")
	)
	(segment
		(start 27.999944 -3.495548)
		(end 27.999944 -7.543038)
		(width 0.508)
		(layer "F.Cu")
		(net "GND")
	)
	(segment
		(start 56.999886 -7.359904)
		(end 57.640982 -8.001)
		(width 0.508)
		(layer "F.Cu")
		(net "GND")
	)
	(segment
		(start 43.999912 -7.54507)
		(end 43.518582 -8.0264)
		(width 0.508)
		(layer "F.Cu")
		(net "GND")
	)
	(segment
		(start 55.999888 -7.660894)
		(end 55.634382 -8.0264)
		(width 0.508)
		(layer "F.Cu")
		(net "GND")
	)
	(segment
		(start 8.999982 -7.3152)
		(end 8.999982 -6.41604)
		(width 0.508)
		(layer "F.Cu")
		(net "GND")
	)
	(segment
		(start 39.99992 -7.506462)
		(end 39.479982 -8.0264)
		(width 0.508)
		(layer "F.Cu")
		(net "GND")
	)
	(segment
		(start 28.999942 -7.47776)
		(end 29.523182 -8.001)
		(width 0.508)
		(layer "F.Cu")
		(net "GND")
	)
	(segment
		(start 51.999896 -7.393686)
		(end 51.417982 -7.9756)
		(width 0.508)
		(layer "F.Cu")
		(net "GND")
	)
	(segment
		(start 36.999926 -7.451344)
		(end 37.549582 -8.001)
		(width 0.508)
		(layer "F.Cu")
		(net "GND")
	)
	(segment
		(start 63.999872 -3.495548)
		(end 63.999872 -7.35711)
		(width 0.508)
		(layer "F.Cu")
		(net "GND")
	)
	(segment
		(start 12.999974 -3.495548)
		(end 12.999974 -7.581392)
		(width 0.508)
		(layer "F.Cu")
		(net "GND")
	)
	(segment
		(start 71.999856 -3.495548)
		(end 71.999856 -7.332726)
		(width 0.508)
		(layer "F.Cu")
		(net "GND")
	)
	(segment
		(start 15.999968 -7.401814)
		(end 15.400782 -8.001)
		(width 0.508)
		(layer "F.Cu")
		(net "GND")
	)
	(segment
		(start 68.999862 -7.26948)
		(end 69.705982 -7.9756)
		(width 0.508)
		(layer "F.Cu")
		(net "GND")
	)
	(segment
		(start 56.999886 -3.495548)
		(end 56.999886 -7.359904)
		(width 0.508)
		(layer "F.Cu")
		(net "GND")
	)
	(segment
		(start 12.999974 -7.581392)
		(end 13.394182 -7.9756)
		(width 0.508)
		(layer "F.Cu")
		(net "GND")
	)
	(segment
		(start 44.99991 -3.495548)
		(end 44.99991 -7.526528)
		(width 0.508)
		(layer "F.Cu")
		(net "GND")
	)
	(segment
		(start 11.999976 -7.617206)
		(end 11.590782 -8.0264)
		(width 0.508)
		(layer "F.Cu")
		(net "GND")
	)
	(segment
		(start 20.999958 -7.580376)
		(end 21.395182 -7.9756)
		(width 0.508)
		(layer "F.Cu")
		(net "GND")
	)
	(segment
		(start 47.999904 -3.495548)
		(end 47.999904 -8.011922)
		(width 0.508)
		(layer "F.Cu")
		(net "GND")
	)
	(segment
		(start 67.999864 -3.495548)
		(end 67.999864 -7.451598)
		(width 0.508)
		(layer "F.Cu")
		(net "GND")
	)
	(segment
		(start 16.999966 -3.495548)
		(end 16.999966 -7.542784)
		(width 0.508)
		(layer "F.Cu")
		(net "GND")
	)
	(segment
		(start 32.999934 -3.495548)
		(end 32.999934 -7.413752)
		(width 0.508)
		(layer "F.Cu")
		(net "GND")
	)
	(segment
		(start 35.999928 -3.495548)
		(end 35.999928 -7.493254)
		(width 0.508)
		(layer "F.Cu")
		(net "GND")
	)
	(segment
		(start 72.999854 -7.591552)
		(end 73.287382 -7.87908)
		(width 0.508)
		(layer "F.Cu")
		(net "GND")
	)
	(segment
		(start 64.99987 -7.358888)
		(end 65.591182 -7.9502)
		(width 0.508)
		(layer "F.Cu")
		(net "GND")
	)
	(segment
		(start 52.999894 -3.495548)
		(end 52.999894 -7.500112)
		(width 0.508)
		(layer "F.Cu")
		(net "GND")
	)
	(segment
		(start 31.999936 -3.495548)
		(end 31.999936 -7.581646)
		(width 0.508)
		(layer "F.Cu")
		(net "GND")
	)
	(segment
		(start 59.99988 -7.496302)
		(end 59.520582 -7.9756)
		(width 0.508)
		(layer "F.Cu")
		(net "GND")
	)
	(segment
		(start 31.999936 -7.581646)
		(end 31.555182 -8.0264)
		(width 0.508)
		(layer "F.Cu")
		(net "GND")
	)
	(segment
		(start 43.999912 -3.495548)
		(end 43.999912 -7.54507)
		(width 0.508)
		(layer "F.Cu")
		(net "GND")
	)
	(segment
		(start 11.999976 -3.495548)
		(end 11.999976 -7.617206)
		(width 0.508)
		(layer "F.Cu")
		(net "GND")
	)
	(segment
		(start 24.99995 -3.495548)
		(end 24.99995 -7.414768)
		(width 0.508)
		(layer "F.Cu")
		(net "GND")
	)
	(segment
		(start 23.999952 -7.50443)
		(end 23.503382 -8.001)
		(width 0.508)
		(layer "F.Cu")
		(net "GND")
	)
	(segment
		(start 8.314182 -6.45668)
		(end 7.999984 -6.142482)
		(width 0.508)
		(layer "F.Cu")
		(net "GND")
	)
	(segment
		(start 35.999928 -7.493254)
		(end 35.492182 -8.001)
		(width 0.508)
		(layer "F.Cu")
		(net "GND")
	)
	(segment
		(start 60.999878 -3.495548)
		(end 60.999878 -7.473696)
		(width 0.508)
		(layer "F.Cu")
		(net "GND")
	)
	(segment
		(start 67.999864 -7.451598)
		(end 67.572382 -7.87908)
		(width 0.508)
		(layer "F.Cu")
		(net "GND")
	)
	(segment
		(start 39.99992 -3.495548)
		(end 39.99992 -7.506462)
		(width 0.508)
		(layer "F.Cu")
		(net "GND")
	)
	(segment
		(start 55.999888 -3.495548)
		(end 55.999888 -7.660894)
		(width 0.508)
		(layer "F.Cu")
		(net "GND")
	)
	(segment
		(start 48.999902 -7.51332)
		(end 49.512982 -8.0264)
		(width 0.508)
		(layer "F.Cu")
		(net "GND")
	)
	(segment
		(start 63.999872 -7.35711)
		(end 63.381382 -7.9756)
		(width 0.508)
		(layer "F.Cu")
		(net "GND")
	)
	(segment
		(start 36.999926 -3.495548)
		(end 36.999926 -7.451344)
		(width 0.508)
		(layer "F.Cu")
		(net "GND")
	)
	(segment
		(start 9.685782 -8.001)
		(end 8.999982 -7.3152)
		(width 0.508)
		(layer "F.Cu")
		(net "GND")
	)
	(segment
		(start 40.999918 -7.412736)
		(end 41.588182 -8.001)
		(width 0.508)
		(layer "F.Cu")
		(net "GND")
	)
	(segment
		(start 8.999982 -6.41604)
		(end 8.999982 -3.495548)
		(width 0.508)
		(layer "F.Cu")
		(net "GND")
	)
	(segment
		(start 27.999944 -7.543038)
		(end 27.516582 -8.0264)
		(width 0.508)
		(layer "F.Cu")
		(net "GND")
	)
	(segment
		(start 75.999848 -7.041134)
		(end 74.99985 -8.041132)
		(width 0.508)
		(layer "F.Cu")
		(net "GND")
	)
	(segment
		(start 40.999918 -3.495548)
		(end 40.999918 -7.412736)
		(width 0.508)
		(layer "F.Cu")
		(net "GND")
	)
	(segment
		(start 19.99996 -3.495548)
		(end 19.99996 -7.669022)
		(width 0.508)
		(layer "F.Cu")
		(net "GND")
	)
	(segment
		(start 16.999966 -7.542784)
		(end 17.432782 -7.9756)
		(width 0.508)
		(layer "F.Cu")
		(net "GND")
	)
	(segment
		(start 60.999878 -7.473696)
		(end 61.552582 -8.0264)
		(width 0.508)
		(layer "F.Cu")
		(net "GND")
	)
	(segment
		(start 68.999862 -3.495548)
		(end 68.999862 -7.26948)
		(width 0.508)
		(layer "F.Cu")
		(net "GND")
	)
	(segment
		(start 48.999902 -3.495548)
		(end 48.999902 -7.51332)
		(width 0.508)
		(layer "F.Cu")
		(net "GND")
	)
	(segment
		(start 71.999856 -7.332726)
		(end 71.356982 -7.9756)
		(width 0.508)
		(layer "F.Cu")
		(net "GND")
	)
	(segment
		(start 7.999984 -6.142482)
		(end 7.999984 -3.495548)
		(width 0.508)
		(layer "F.Cu")
		(net "GND")
	)
	(segment
		(start 64.99987 -3.495548)
		(end 64.99987 -7.358888)
		(width 0.508)
		(layer "F.Cu")
		(net "GND")
	)
	(via
		(at 8.982202 -9.64184)
		(size 0.5588)
		(drill 0.3048)
		(layers "F.Cu" "B.Cu")
		(net "GND")
	)
	(via
		(at 83.726782 -7.8994)
		(size 0.5588)
		(drill 0.3048)
		(layers "F.Cu" "B.Cu")
		(net "GND")
	)
	(via
		(at 86.000082 -8.1407)
		(size 0.5588)
		(drill 0.3048)
		(layers "F.Cu" "B.Cu")
		(net "GND")
	)
	(via
		(at 49.512982 -8.0264)
		(size 0.5588)
		(drill 0.3048)
		(layers "F.Cu" "B.Cu")
		(net "GND")
	)
	(via
		(at 59.520582 -7.9756)
		(size 0.5588)
		(drill 0.3048)
		(layers "F.Cu" "B.Cu")
		(net "GND")
	)
	(via
		(at 27.516582 -8.0264)
		(size 0.5588)
		(drill 0.3048)
		(layers "F.Cu" "B.Cu")
		(net "GND")
	)
	(via
		(at 41.588182 -8.001)
		(size 0.5588)
		(drill 0.3048)
		(layers "F.Cu" "B.Cu")
		(net "GND")
	)
	(via
		(at 39.479982 -8.0264)
		(size 0.5588)
		(drill 0.3048)
		(layers "F.Cu" "B.Cu")
		(net "GND")
	)
	(via
		(at 74.99985 -8.041132)
		(size 0.5588)
		(drill 0.3048)
		(layers "F.Cu" "B.Cu")
		(net "GND")
	)
	(via
		(at 23.503382 -8.001)
		(size 0.5588)
		(drill 0.3048)
		(layers "F.Cu" "B.Cu")
		(net "GND")
	)
	(via
		(at 17.432782 -7.9756)
		(size 0.5588)
		(drill 0.3048)
		(layers "F.Cu" "B.Cu")
		(net "GND")
	)
	(via
		(at 13.394182 -7.9756)
		(size 0.5588)
		(drill 0.3048)
		(layers "F.Cu" "B.Cu")
		(net "GND")
	)
	(via
		(at 25.586182 -8.001)
		(size 0.5588)
		(drill 0.3048)
		(layers "F.Cu" "B.Cu")
		(net "GND")
	)
	(via
		(at 69.705982 -7.9756)
		(size 0.5588)
		(drill 0.3048)
		(layers "F.Cu" "B.Cu")
		(net "GND")
	)
	(via
		(at 73.287382 -7.87908)
		(size 0.5588)
		(drill 0.3048)
		(layers "F.Cu" "B.Cu")
		(net "GND")
	)
	(via
		(at 21.395182 -7.9756)
		(size 0.5588)
		(drill 0.3048)
		(layers "F.Cu" "B.Cu")
		(net "GND")
	)
	(via
		(at 37.549582 -8.001)
		(size 0.5588)
		(drill 0.3048)
		(layers "F.Cu" "B.Cu")
		(net "GND")
	)
	(via
		(at 19.617182 -8.0518)
		(size 0.5588)
		(drill 0.3048)
		(layers "F.Cu" "B.Cu")
		(net "GND")
	)
	(via
		(at 47.999904 -8.011922)
		(size 0.5588)
		(drill 0.3048)
		(layers "F.Cu" "B.Cu")
		(net "GND")
	)
	(via
		(at 53.500782 -8.001)
		(size 0.5588)
		(drill 0.3048)
		(layers "F.Cu" "B.Cu")
		(net "GND")
	)
	(via
		(at 29.523182 -8.001)
		(size 0.5588)
		(drill 0.3048)
		(layers "F.Cu" "B.Cu")
		(net "GND")
	)
	(via
		(at 65.591182 -7.9502)
		(size 0.5588)
		(drill 0.3048)
		(layers "F.Cu" "B.Cu")
		(net "GND")
	)
	(via
		(at 43.518582 -8.0264)
		(size 0.5588)
		(drill 0.3048)
		(layers "F.Cu" "B.Cu")
		(net "GND")
	)
	(via
		(at 9.685782 -8.001)
		(size 0.5588)
		(drill 0.3048)
		(layers "F.Cu" "B.Cu")
		(net "GND")
	)
	(via
		(at 33.612582 -8.0264)
		(size 0.5588)
		(drill 0.3048)
		(layers "F.Cu" "B.Cu")
		(net "GND")
	)
	(via
		(at 35.492182 -8.001)
		(size 0.5588)
		(drill 0.3048)
		(layers "F.Cu" "B.Cu")
		(net "GND")
	)
	(via
		(at 45.499782 -8.0264)
		(size 0.5588)
		(drill 0.3048)
		(layers "F.Cu" "B.Cu")
		(net "GND")
	)
	(via
		(at 51.417982 -7.9756)
		(size 0.5588)
		(drill 0.3048)
		(layers "F.Cu" "B.Cu")
		(net "GND")
	)
	(via
		(at 15.400782 -8.001)
		(size 0.5588)
		(drill 0.3048)
		(layers "F.Cu" "B.Cu")
		(net "GND")
	)
	(via
		(at 57.640982 -8.001)
		(size 0.5588)
		(drill 0.3048)
		(layers "F.Cu" "B.Cu")
		(net "GND")
	)
	(via
		(at 61.552582 -8.0264)
		(size 0.5588)
		(drill 0.3048)
		(layers "F.Cu" "B.Cu")
		(net "GND")
	)
	(via
		(at 71.356982 -7.9756)
		(size 0.5588)
		(drill 0.3048)
		(layers "F.Cu" "B.Cu")
		(net "GND")
	)
	(via
		(at 31.555182 -8.0264)
		(size 0.5588)
		(drill 0.3048)
		(layers "F.Cu" "B.Cu")
		(net "GND")
	)
	(via
		(at 67.572382 -7.87908)
		(size 0.5588)
		(drill 0.3048)
		(layers "F.Cu" "B.Cu")
		(net "GND")
	)
	(via
		(at 55.634382 -8.0264)
		(size 0.5588)
		(drill 0.3048)
		(layers "F.Cu" "B.Cu")
		(net "GND")
	)
	(via
		(at 11.590782 -8.0264)
		(size 0.5588)
		(drill 0.3048)
		(layers "F.Cu" "B.Cu")
		(net "GND")
	)
	(via
		(at 63.381382 -7.9756)
		(size 0.5588)
		(drill 0.3048)
		(layers "F.Cu" "B.Cu")
		(net "GND")
	)
	(segment
		(start 38.999922 -7.54634)
		(end 39.479982 -8.0264)
		(width 0.508)
		(layer "B.Cu")
		(net "GND")
	)
	(segment
		(start 83.000088 -3.114548)
		(end 83.000088 -7.172706)
		(width 0.508)
		(layer "B.Cu")
		(net "GND")
	)
	(segment
		(start 53.999892 -7.50189)
		(end 53.500782 -8.001)
		(width 0.508)
		(layer "B.Cu")
		(net "GND")
	)
	(segment
		(start 58.999882 -7.4549)
		(end 59.520582 -7.9756)
		(width 0.508)
		(layer "B.Cu")
		(net "GND")
	)
	(segment
		(start 21.999956 -7.370826)
		(end 21.395182 -7.9756)
		(width 0.508)
		(layer "B.Cu")
		(net "GND")
	)
	(segment
		(start 29.99994 -7.524242)
		(end 29.523182 -8.001)
		(width 0.508)
		(layer "B.Cu")
		(net "GND")
	)
	(segment
		(start 38.999922 -3.114548)
		(end 38.999922 -7.54634)
		(width 0.508)
		(layer "B.Cu")
		(net "GND")
	)
	(segment
		(start 42.999914 -3.114548)
		(end 42.999914 -7.507732)
		(width 0.508)
		(layer "B.Cu")
		(net "GND")
	)
	(segment
		(start 83.000088 -7.172706)
		(end 83.726782 -7.8994)
		(width 0.508)
		(layer "B.Cu")
		(net "GND")
	)
	(segment
		(start 66.999866 -7.306564)
		(end 67.572382 -7.87908)
		(width 0.508)
		(layer "B.Cu")
		(net "GND")
	)
	(segment
		(start 18.999962 -3.114548)
		(end 18.999962 -7.43458)
		(width 0.508)
		(layer "B.Cu")
		(net "GND")
	)
	(segment
		(start 9.99998 -3.114548)
		(end 9.99998 -7.686802)
		(width 0.508)
		(layer "B.Cu")
		(net "GND")
	)
	(segment
		(start 13.999972 -7.36981)
		(end 13.394182 -7.9756)
		(width 0.508)
		(layer "B.Cu")
		(net "GND")
	)
	(segment
		(start 30.999938 -7.471156)
		(end 31.555182 -8.0264)
		(width 0.508)
		(layer "B.Cu")
		(net "GND")
	)
	(segment
		(start 33.999932 -7.63905)
		(end 33.612582 -8.0264)
		(width 0.508)
		(layer "B.Cu")
		(net "GND")
	)
	(segment
		(start 5.999988 -7.215886)
		(end 5.999988 -3.114548)
		(width 0.508)
		(layer "B.Cu")
		(net "GND")
	)
	(segment
		(start 22.999954 -3.114548)
		(end 22.999954 -7.497572)
		(width 0.508)
		(layer "B.Cu")
		(net "GND")
	)
	(segment
		(start 69.99986 -7.681722)
		(end 69.705982 -7.9756)
		(width 0.508)
		(layer "B.Cu")
		(net "GND")
	)
	(segment
		(start 33.999932 -3.114548)
		(end 33.999932 -7.63905)
		(width 0.508)
		(layer "B.Cu")
		(net "GND")
	)
	(segment
		(start 50.999898 -7.557516)
		(end 51.417982 -7.9756)
		(width 0.508)
		(layer "B.Cu")
		(net "GND")
	)
	(segment
		(start 30.999938 -3.114548)
		(end 30.999938 -7.471156)
		(width 0.508)
		(layer "B.Cu")
		(net "GND")
	)
	(segment
		(start 49.9999 -3.114548)
		(end 49.9999 -7.539482)
		(width 0.508)
		(layer "B.Cu")
		(net "GND")
	)
	(segment
		(start 26.999946 -3.114548)
		(end 26.999946 -7.509764)
		(width 0.508)
		(layer "B.Cu")
		(net "GND")
	)
	(segment
		(start 8.425942 -9.64184)
		(end 7.682992 -8.89889)
		(width 0.508)
		(layer "B.Cu")
		(net "GND")
	)
	(segment
		(start 37.999924 -7.550658)
		(end 37.549582 -8.001)
		(width 0.508)
		(layer "B.Cu")
		(net "GND")
	)
	(segment
		(start 46.999906 -3.114548)
		(end 46.999906 -7.011924)
		(width 0.508)
		(layer "B.Cu")
		(net "GND")
	)
	(segment
		(start 57.999884 -3.114548)
		(end 57.999884 -7.642098)
		(width 0.508)
		(layer "B.Cu")
		(net "GND")
	)
	(segment
		(start 29.99994 -3.114548)
		(end 29.99994 -7.524242)
		(width 0.508)
		(layer "B.Cu")
		(net "GND")
	)
	(segment
		(start 74.99985 -3.114548)
		(end 74.99985 -8.041132)
		(width 0.508)
		(layer "B.Cu")
		(net "GND")
	)
	(segment
		(start 54.99989 -7.391908)
		(end 55.634382 -8.0264)
		(width 0.508)
		(layer "B.Cu")
		(net "GND")
	)
	(segment
		(start 7.682992 -8.89889)
		(end 5.999988 -7.215886)
		(width 0.508)
		(layer "B.Cu")
		(net "GND")
	)
	(segment
		(start 69.99986 -3.114548)
		(end 69.99986 -7.681722)
		(width 0.508)
		(layer "B.Cu")
		(net "GND")
	)
	(segment
		(start 61.999876 -7.579106)
		(end 61.552582 -8.0264)
		(width 0.508)
		(layer "B.Cu")
		(net "GND")
	)
	(segment
		(start 70.999858 -7.618476)
		(end 71.356982 -7.9756)
		(width 0.508)
		(layer "B.Cu")
		(net "GND")
	)
	(segment
		(start 65.999868 -3.114548)
		(end 65.999868 -7.541514)
		(width 0.508)
		(layer "B.Cu")
		(net "GND")
	)
	(segment
		(start 62.999874 -7.594092)
		(end 63.381382 -7.9756)
		(width 0.508)
		(layer "B.Cu")
		(net "GND")
	)
	(segment
		(start 61.999876 -3.114548)
		(end 61.999876 -7.579106)
		(width 0.508)
		(layer "B.Cu")
		(net "GND")
	)
	(segment
		(start 70.999858 -3.990848)
		(end 70.999858 -7.618476)
		(width 0.508)
		(layer "B.Cu")
		(net "GND")
	)
	(segment
		(start 34.99993 -7.508748)
		(end 35.492182 -8.001)
		(width 0.508)
		(layer "B.Cu")
		(net "GND")
	)
	(segment
		(start 49.9999 -7.539482)
		(end 49.512982 -8.0264)
		(width 0.508)
		(layer "B.Cu")
		(net "GND")
	)
	(segment
		(start 41.999916 -3.114548)
		(end 41.999916 -7.589266)
		(width 0.508)
		(layer "B.Cu")
		(net "GND")
	)
	(segment
		(start 66.999866 -3.114548)
		(end 66.999866 -7.306564)
		(width 0.508)
		(layer "B.Cu")
		(net "GND")
	)
	(segment
		(start 14.99997 -7.600188)
		(end 15.400782 -8.001)
		(width 0.508)
		(layer "B.Cu")
		(net "GND")
	)
	(segment
		(start 73.999852 -3.114548)
		(end 73.999852 -7.16661)
		(width 0.508)
		(layer "B.Cu")
		(net "GND")
	)
	(segment
		(start 25.999948 -7.587234)
		(end 25.586182 -8.001)
		(width 0.508)
		(layer "B.Cu")
		(net "GND")
	)
	(segment
		(start 45.999908 -3.114548)
		(end 45.999908 -7.526274)
		(width 0.508)
		(layer "B.Cu")
		(net "GND")
	)
	(segment
		(start 62.999874 -3.114548)
		(end 62.999874 -7.594092)
		(width 0.508)
		(layer "B.Cu")
		(net "GND")
	)
	(segment
		(start 6.999986 -3.990848)
		(end 6.999986 -6.356604)
		(width 0.508)
		(layer "B.Cu")
		(net "GND")
	)
	(segment
		(start 53.999892 -3.114548)
		(end 53.999892 -7.50189)
		(width 0.508)
		(layer "B.Cu")
		(net "GND")
	)
	(segment
		(start 17.999964 -3.114548)
		(end 17.999964 -7.408418)
		(width 0.508)
		(layer "B.Cu")
		(net "GND")
	)
	(segment
		(start 7.682992 -7.03961)
		(end 7.682992 -8.89889)
		(width 0.508)
		(layer "B.Cu")
		(net "GND")
	)
	(segment
		(start 18.999962 -7.43458)
		(end 19.617182 -8.0518)
		(width 0.508)
		(layer "B.Cu")
		(net "GND")
	)
	(segment
		(start 65.999868 -7.541514)
		(end 65.591182 -7.9502)
		(width 0.508)
		(layer "B.Cu")
		(net "GND")
	)
	(segment
		(start 13.999972 -3.114548)
		(end 13.999972 -7.36981)
		(width 0.508)
		(layer "B.Cu")
		(net "GND")
	)
	(segment
		(start 8.982202 -9.64184)
		(end 8.425942 -9.64184)
		(width 0.508)
		(layer "B.Cu")
		(net "GND")
	)
	(segment
		(start 34.99993 -3.114548)
		(end 34.99993 -7.508748)
		(width 0.508)
		(layer "B.Cu")
		(net "GND")
	)
	(segment
		(start 26.999946 -7.509764)
		(end 27.516582 -8.0264)
		(width 0.508)
		(layer "B.Cu")
		(net "GND")
	)
	(segment
		(start 10.999978 -7.435596)
		(end 11.590782 -8.0264)
		(width 0.508)
		(layer "B.Cu")
		(net "GND")
	)
	(segment
		(start 25.999948 -3.114548)
		(end 25.999948 -7.587234)
		(width 0.508)
		(layer "B.Cu")
		(net "GND")
	)
	(segment
		(start 50.999898 -3.114548)
		(end 50.999898 -7.557516)
		(width 0.508)
		(layer "B.Cu")
		(net "GND")
	)
	(segment
		(start 45.999908 -7.526274)
		(end 45.499782 -8.0264)
		(width 0.508)
		(layer "B.Cu")
		(net "GND")
	)
	(segment
		(start 10.999978 -3.114548)
		(end 10.999978 -7.435596)
		(width 0.508)
		(layer "B.Cu")
		(net "GND")
	)
	(segment
		(start 86.000082 -3.114548)
		(end 86.000082 -8.1407)
		(width 0.508)
		(layer "B.Cu")
		(net "GND")
	)
	(segment
		(start 42.999914 -7.507732)
		(end 43.518582 -8.0264)
		(width 0.508)
		(layer "B.Cu")
		(net "GND")
	)
	(segment
		(start 41.999916 -7.589266)
		(end 41.588182 -8.001)
		(width 0.508)
		(layer "B.Cu")
		(net "GND")
	)
	(segment
		(start 73.999852 -7.16661)
		(end 73.287382 -7.87908)
		(width 0.508)
		(layer "B.Cu")
		(net "GND")
	)
	(segment
		(start 17.999964 -7.408418)
		(end 17.432782 -7.9756)
		(width 0.508)
		(layer "B.Cu")
		(net "GND")
	)
	(segment
		(start 57.999884 -7.642098)
		(end 57.640982 -8.001)
		(width 0.508)
		(layer "B.Cu")
		(net "GND")
	)
	(segment
		(start 9.99998 -7.686802)
		(end 9.685782 -8.001)
		(width 0.508)
		(layer "B.Cu")
		(net "GND")
	)
	(segment
		(start 21.999956 -3.114548)
		(end 21.999956 -7.370826)
		(width 0.508)
		(layer "B.Cu")
		(net "GND")
	)
	(segment
		(start 6.999986 -6.356604)
		(end 7.682992 -7.03961)
		(width 0.508)
		(layer "B.Cu")
		(net "GND")
	)
	(segment
		(start 14.99997 -3.114548)
		(end 14.99997 -7.600188)
		(width 0.508)
		(layer "B.Cu")
		(net "GND")
	)
	(segment
		(start 22.999954 -7.497572)
		(end 23.503382 -8.001)
		(width 0.508)
		(layer "B.Cu")
		(net "GND")
	)
	(segment
		(start 46.999906 -7.011924)
		(end 47.999904 -8.011922)
		(width 0.508)
		(layer "B.Cu")
		(net "GND")
	)
	(segment
		(start 54.99989 -3.114548)
		(end 54.99989 -7.391908)
		(width 0.508)
		(layer "B.Cu")
		(net "GND")
	)
	(segment
		(start 37.999924 -3.114548)
		(end 37.999924 -7.550658)
		(width 0.508)
		(layer "B.Cu")
		(net "GND")
	)
	(segment
		(start 58.999882 -3.114548)
		(end 58.999882 -7.4549)
		(width 0.508)
		(layer "B.Cu")
		(net "GND")
	)
	(segment
		(start 52.218082 -21.75256)
		(end 52.218082 -18.15084)
		(width 0.1397)
		(layer "B.Cu")
		(net "CLK_100M_CLKBUFF_ENET_DP")
	)
	(segment
		(start 52.789582 -21.9964)
		(end 52.461922 -21.9964)
		(width 0.1397)
		(layer "B.Cu")
		(net "CLK_100M_CLKBUFF_ENET_DP")
	)
	(segment
		(start 52.999894 -5.747258)
		(end 52.999894 -3.114548)
		(width 0.1397)
		(layer "B.Cu")
		(net "CLK_100M_CLKBUFF_ENET_DP")
	)
	(segment
		(start 52.461922 -21.9964)
		(end 52.218082 -21.75256)
		(width 0.1397)
		(layer "B.Cu")
		(net "CLK_100M_CLKBUFF_ENET_DP")
	)
	(segment
		(start 53.170582 -17.19834)
		(end 53.170582 -14.73327)
		(width 0.1397)
		(layer "B.Cu")
		(net "CLK_100M_CLKBUFF_ENET_DP")
	)
	(segment
		(start 53.170582 -14.73327)
		(end 52.671472 -14.23416)
		(width 0.1397)
		(layer "B.Cu")
		(net "CLK_100M_CLKBUFF_ENET_DP")
	)
	(segment
		(start 52.218082 -18.15084)
		(end 53.170582 -17.19834)
		(width 0.1397)
		(layer "B.Cu")
		(net "CLK_100M_CLKBUFF_ENET_DP")
	)
	(segment
		(start 52.671472 -14.23416)
		(end 52.671472 -6.07568)
		(width 0.1397)
		(layer "B.Cu")
		(net "CLK_100M_CLKBUFF_ENET_DP")
	)
	(segment
		(start 53.000402 -21.149564)
		(end 52.992528 -21.149564)
		(width 0.1397)
		(layer "B.Cu")
		(net "CLK_100M_CLKBUFF_ENET_DP")
	)
	(segment
		(start 52.992528 -21.793454)
		(end 52.789582 -21.9964)
		(width 0.1397)
		(layer "B.Cu")
		(net "CLK_100M_CLKBUFF_ENET_DP")
	)
	(segment
		(start 52.671472 -6.07568)
		(end 52.999894 -5.747258)
		(width 0.1397)
		(layer "B.Cu")
		(net "CLK_100M_CLKBUFF_ENET_DP")
	)
	(segment
		(start 52.992528 -21.149564)
		(end 52.992528 -21.793454)
		(width 0.1397)
		(layer "B.Cu")
		(net "CLK_100M_CLKBUFF_ENET_DP")
	)
	(segment
		(start 50.630582 -15.9512)
		(end 50.630582 -7.2644)
		(width 0.127)
		(layer "F.Cu")
		(net "PCIE_RSVD_A37")
	)
	(segment
		(start 51.000152 -18.650204)
		(end 50.999898 -18.650204)
		(width 0.127)
		(layer "F.Cu")
		(net "PCIE_RSVD_A37")
	)
	(segment
		(start 50.630582 -7.2644)
		(end 50.999898 -6.895084)
		(width 0.127)
		(layer "F.Cu")
		(net "PCIE_RSVD_A37")
	)
	(segment
		(start 50.999898 -18.650204)
		(end 50.999898 -16.320516)
		(width 0.127)
		(layer "F.Cu")
		(net "PCIE_RSVD_A37")
	)
	(segment
		(start 50.999898 -16.320516)
		(end 50.630582 -15.9512)
		(width 0.127)
		(layer "F.Cu")
		(net "PCIE_RSVD_A37")
	)
	(segment
		(start 50.999898 -6.895084)
		(end 50.999898 -3.495548)
		(width 0.127)
		(layer "F.Cu")
		(net "PCIE_RSVD_A37")
	)
	(segment
		(start 83.879182 -9.8552)
		(end 82.00009 -7.976108)
		(width 0.10795)
		(layer "F.Cu")
		(net "CPU_RXD")
	)
	(segment
		(start 82.520028 -16.649954)
		(end 83.879182 -15.2908)
		(width 0.10795)
		(layer "F.Cu")
		(net "CPU_RXD")
	)
	(segment
		(start 83.879182 -15.2908)
		(end 83.879182 -9.8552)
		(width 0.10795)
		(layer "F.Cu")
		(net "CPU_RXD")
	)
	(segment
		(start 82.00009 -7.976108)
		(end 82.00009 -3.495548)
		(width 0.10795)
		(layer "F.Cu")
		(net "CPU_RXD")
	)
	(segment
		(start 81.999582 -16.649954)
		(end 82.520028 -16.649954)
		(width 0.10795)
		(layer "F.Cu")
		(net "CPU_RXD")
	)
	(segment
		(start 78.999842 -18.650204)
		(end 78.999588 -18.650204)
		(width 0.10795)
		(layer "F.Cu")
		(net "PCIE_RESET#")
	)
	(segment
		(start 79.434182 -8.6106)
		(end 79.434182 -6.2738)
		(width 0.10795)
		(layer "F.Cu")
		(net "PCIE_RESET#")
	)
	(segment
		(start 78.999588 -18.650204)
		(end 78.474062 -18.124678)
		(width 0.10795)
		(layer "F.Cu")
		(net "PCIE_RESET#")
	)
	(segment
		(start 79.000096 -5.839714)
		(end 79.000096 -3.495548)
		(width 0.10795)
		(layer "F.Cu")
		(net "PCIE_RESET#")
	)
	(segment
		(start 77.630782 -10.414)
		(end 79.434182 -8.6106)
		(width 0.10795)
		(layer "F.Cu")
		(net "PCIE_RESET#")
	)
	(segment
		(start 78.474062 -15.90548)
		(end 77.630782 -15.0622)
		(width 0.10795)
		(layer "F.Cu")
		(net "PCIE_RESET#")
	)
	(segment
		(start 79.434182 -6.2738)
		(end 79.000096 -5.839714)
		(width 0.10795)
		(layer "F.Cu")
		(net "PCIE_RESET#")
	)
	(segment
		(start 78.474062 -18.124678)
		(end 78.474062 -15.90548)
		(width 0.10795)
		(layer "F.Cu")
		(net "PCIE_RESET#")
	)
	(segment
		(start 77.630782 -15.0622)
		(end 77.630782 -10.414)
		(width 0.10795)
		(layer "F.Cu")
		(net "PCIE_RESET#")
	)
	(segment
		(start 81.000092 -7.45871)
		(end 81.000092 -3.495548)
		(width 0.10795)
		(layer "F.Cu")
		(net "SLOT_ID2")
	)
	(segment
		(start 83.625182 -15.1638)
		(end 83.625182 -10.0838)
		(width 0.10795)
		(layer "F.Cu")
		(net "SLOT_ID2")
	)
	(segment
		(start 80.999838 -16.297656)
		(end 81.390744 -15.90675)
		(width 0.10795)
		(layer "F.Cu")
		(net "SLOT_ID2")
	)
	(segment
		(start 82.882232 -15.90675)
		(end 83.625182 -15.1638)
		(width 0.10795)
		(layer "F.Cu")
		(net "SLOT_ID2")
	)
	(segment
		(start 83.625182 -10.0838)
		(end 81.000092 -7.45871)
		(width 0.10795)
		(layer "F.Cu")
		(net "SLOT_ID2")
	)
	(segment
		(start 81.000092 -18.650204)
		(end 80.999838 -18.650204)
		(width 0.10795)
		(layer "F.Cu")
		(net "SLOT_ID2")
	)
	(segment
		(start 80.999838 -18.650204)
		(end 80.999838 -16.297656)
		(width 0.10795)
		(layer "F.Cu")
		(net "SLOT_ID2")
	)
	(segment
		(start 81.390744 -15.90675)
		(end 82.882232 -15.90675)
		(width 0.10795)
		(layer "F.Cu")
		(net "SLOT_ID2")
	)
	(zone
		(net "P12V")
		(layer "F.Cu")
		(hatch none 0.5)
		(connect_pads
			(clearance 0.5)
		)
		(min_thickness 0.25)
		(fill yes
			(thermal_gap 0.5)
			(thermal_bridge_width 0.5)
			(island_removal_mode 0)
		)
		(polygon
			(pts
				(xy 5.990082 -8.4201)
				(arc
					(start 5.779008 -8.631174)
					(mid 5.5961 -8.84603)
					(end 5.381244 -9.028938)
				)
				(xy 2.548382 -11.8618) (xy 2.548382 -17.0434) (xy 3.132582 -17.6276) (xy 3.132582 -19.7104) (xy 3.970782 -20.5486)
				(xy 8.034782 -20.5486) (xy 9.139682 -19.4437) (xy 9.139682 -10.8839) (xy 9.139682 -10.72388) (xy 8.456422 -10.04062)
				(xy 8.456422 -9.56818) (xy 8.456422 -7.9883) (xy 8.455152 -7.98703) (xy 8.455152 -7.44982) (xy 7.761732 -6.7564)
				(xy 7.182612 -6.17728) (xy 6.373622 -6.17728) (xy 5.990082 -6.56082)
			)
		)
	)
	(zone
		(layer "F.Cu")
		(hatch none 0.5)
		(connect_pads
			(clearance 0)
		)
		(min_thickness 0.25)
		(keepout
			(tracks allowed)
			(vias allowed)
			(pads allowed)
			(copperpour allowed)
			(footprints not_allowed)
		)
		(placement
			(enabled no)
			(sheetname "")
		)
		(fill
			(thermal_gap 0.5)
			(thermal_bridge_width 0.5)
			(island_removal_mode 0)
		)
		(polygon
			(pts
				(arc
					(start 0.999998 -27.100022)
					(mid 0.292893 -26.807129)
					(end 0 -26.100024)
				)
				(arc
					(start 0 -9.59993)
					(mid 0.292893 -8.892825)
					(end 0.999998 -8.599932)
				)
				(xy 2.999994 -8.599932) (xy 2.999994 -16.225012)
				(arc
					(start 94.000066 -16.225012)
					(mid 94.707171 -16.517905)
					(end 95.000064 -17.22501)
				)
				(arc
					(start 95.000064 -26.100024)
					(mid 94.707171 -26.807129)
					(end 94.000066 -27.100022)
				)
				(arc
					(start 58.50001 -27.100022)
					(mid 57.792905 -26.807129)
					(end 57.500012 -26.100024)
				)
				(arc
					(start 57.500012 -26.100024)
					(mid 57.207119 -25.392919)
					(end 56.500014 -25.100026)
				)
				(arc
					(start 38.50005 -25.100026)
					(mid 37.792945 -25.392919)
					(end 37.500052 -26.100024)
				)
				(arc
					(start 37.500052 -26.100024)
					(mid 37.207159 -26.807129)
					(end 36.500054 -27.100022)
				)
			)
		)
	)
	(zone
		(net "P12V")
		(layer "F.Cu")
		(hatch none 0.5)
		(connect_pads
			(clearance 0.5)
		)
		(min_thickness 0.25)
		(fill yes
			(thermal_gap 0.5)
			(thermal_bridge_width 0.5)
			(island_removal_mode 0)
		)
		(polygon
			(pts
				(xy 86.698582 -6.096) (xy 86.546182 -6.2484) (xy 86.546182 -8.29564) (xy 85.555582 -9.28624) (xy 84.88172 -9.960102)
				(xy 84.88172 -18.668238) (xy 85.555582 -19.3421) (xy 85.555582 -23.876) (xy 86.012782 -24.3332)
				(xy 92.337382 -24.3332) (xy 93.581982 -23.0886) (xy 93.581982 -17.44726) (xy 93.155262 -17.02054)
				(xy 89.9033 -17.02054) (xy 88.86698 -15.98422) (xy 88.86698 -7.66826) (xy 88.888316 -7.646924) (xy 88.887808 -7.599934)
				(xy 88.887808 -6.2992) (xy 88.628982 -6.2992) (xy 88.425782 -6.096)
			)
		)
	)
	(zone
		(layers "F.Cu" "B.Cu")
		(hatch none 0.5)
		(connect_pads
			(clearance 0)
		)
		(min_thickness 0.25)
		(keepout
			(tracks allowed)
			(vias allowed)
			(pads allowed)
			(copperpour allowed)
			(footprints not_allowed)
		)
		(placement
			(enabled no)
			(sheetname "")
		)
		(fill yes
			(thermal_gap 0.5)
			(thermal_bridge_width 0.5)
			(island_removal_mode 0)
		)
		(polygon
			(pts
				(arc
					(start 90.65006 -16.225012)
					(mid 89.942955 -15.932119)
					(end 89.650062 -15.225014)
				)
				(xy 89.650062 -8.599932) (xy 2.999994 -8.599932) (xy 2.999994 -16.225012)
			)
		)
	)
	(zone
		(layers "F.Cu" "B.Cu" "In1.Cu" "In2.Cu")
		(name "Package Keepin")
		(hatch none 0.5)
		(connect_pads
			(clearance 0)
		)
		(min_thickness 0.25)
		(keepout
			(tracks allowed)
			(vias allowed)
			(pads allowed)
			(copperpour allowed)
			(footprints allowed)
		)
		(placement
			(enabled no)
			(sheetname "")
		)
		(fill
			(thermal_gap 0.5)
			(thermal_bridge_width 0.5)
			(island_removal_mode 0)
		)
		(polygon
			(pts
				(xy 88.126062 -1.524) (xy 79.973932 -1.524)
				(arc
					(start 79.973932 -7.450074)
					(mid 77.499972 -9.924034)
					(end 75.026012 -7.450074)
				)
				(xy 75.026012 -1.524) (xy 6.874002 -1.524)
				(arc
					(start 6.874002 -7.599934)
					(mid 6.13474 -9.38467)
					(end 4.350004 -10.123932)
				)
				(xy 1.524 -10.123932) (xy 1.524 -25.576022)
				(arc
					(start 36.030916 -25.576022)
					(mid 36.911253 -24.138666)
					(end 38.50005 -23.576026)
				)
				(arc
					(start 56.500014 -23.576026)
					(mid 58.088712 -24.138748)
					(end 58.968894 -25.576022)
				)
				(xy 93.476064 -25.576022) (xy 93.476064 -17.749012)
				(arc
					(start 90.65006 -17.749012)
					(mid 88.865324 -17.00975)
					(end 88.126062 -15.225014)
				)
			)
		)
	)
	(zone
		(layers "F.Cu" "B.Cu" "In1.Cu" "In2.Cu")
		(name "Route Keepin")
		(hatch none 0.5)
		(connect_pads
			(clearance 0)
		)
		(min_thickness 0.25)
		(keepout
			(tracks allowed)
			(vias allowed)
			(pads allowed)
			(copperpour allowed)
			(footprints allowed)
		)
		(placement
			(enabled no)
			(sheetname "")
		)
		(fill
			(thermal_gap 0.5)
			(thermal_bridge_width 0.5)
			(island_removal_mode 0)
		)
		(polygon
			(pts
				(xy 88.888062 -0.815848) (xy 88.834214 -0.762) (xy 79.26578 -0.762) (xy 79.211932 -0.815848)
				(arc
					(start 79.211932 -7.450074)
					(mid 77.499972 -9.162034)
					(end 75.788012 -7.450074)
				)
				(xy 75.788012 -0.815848) (xy 75.734164 -0.762) (xy 6.165596 -0.762) (xy 6.112002 -0.815594)
				(arc
					(start 6.112002 -7.599934)
					(mid 5.595925 -8.845855)
					(end 4.350004 -9.361932)
				)
				(arc
					(start 0.999998 -9.361932)
					(mid 0.831708 -9.43164)
					(end 0.762 -9.59993)
				)
				(arc
					(start 0.762 -26.100024)
					(mid 0.831708 -26.268314)
					(end 0.999998 -26.338022)
				)
				(arc
					(start 36.500054 -26.338022)
					(mid 36.668344 -26.268314)
					(end 36.738052 -26.100024)
				)
				(arc
					(start 36.738052 -26.100024)
					(mid 37.254129 -24.854103)
					(end 38.50005 -24.338026)
				)
				(arc
					(start 56.500014 -24.338026)
					(mid 57.745935 -24.854103)
					(end 58.262012 -26.100024)
				)
				(arc
					(start 58.262012 -26.100024)
					(mid 58.33172 -26.268314)
					(end 58.50001 -26.338022)
				)
				(arc
					(start 94.000066 -26.338022)
					(mid 94.168356 -26.268314)
					(end 94.238064 -26.100024)
				)
				(arc
					(start 94.238064 -17.22501)
					(mid 94.168356 -17.05672)
					(end 94.000066 -16.987012)
				)
				(arc
					(start 90.65006 -16.987012)
					(mid 89.404139 -16.470935)
					(end 88.888062 -15.225014)
				)
			)
		)
	)
	(zone
		(layer "B.Cu")
		(hatch none 0.5)
		(connect_pads
			(clearance 0)
		)
		(min_thickness 0.25)
		(keepout
			(tracks allowed)
			(vias allowed)
			(pads allowed)
			(copperpour allowed)
			(footprints not_allowed)
		)
		(placement
			(enabled no)
			(sheetname "")
		)
		(fill
			(thermal_gap 0.5)
			(thermal_bridge_width 0.5)
			(island_removal_mode 0)
		)
		(polygon
			(pts
				(xy 2.999994 -16.225012) (xy 2.999994 -8.599932)
				(arc
					(start 0.999998 -8.599932)
					(mid 0.292893 -8.892825)
					(end 0 -9.59993)
				)
				(arc
					(start 0 -26.100024)
					(mid 0.292893 -26.807129)
					(end 0.999998 -27.100022)
				)
				(arc
					(start 36.500054 -27.100022)
					(mid 37.207159 -26.807129)
					(end 37.500052 -26.100024)
				)
				(arc
					(start 37.500052 -26.100024)
					(mid 37.792945 -25.392919)
					(end 38.50005 -25.100026)
				)
				(arc
					(start 56.500014 -25.100026)
					(mid 57.207119 -25.392919)
					(end 57.500012 -26.100024)
				)
				(arc
					(start 57.500012 -26.100024)
					(mid 57.792905 -26.807129)
					(end 58.50001 -27.100022)
				)
				(arc
					(start 94.000066 -27.100022)
					(mid 94.707171 -26.807129)
					(end 95.000064 -26.100024)
				)
				(arc
					(start 95.000064 -17.22501)
					(mid 94.707171 -16.517905)
					(end 94.000066 -16.225012)
				)
			)
		)
	)
	(zone
		(net "P12V")
		(layer "B.Cu")
		(hatch none 0.5)
		(connect_pads
			(clearance 0.5)
		)
		(min_thickness 0.25)
		(fill yes
			(thermal_gap 0.5)
			(thermal_bridge_width 0.5)
			(island_removal_mode 0)
		)
		(polygon
			(pts
				(arc
					(start 5.587746 -8.85444)
					(mid 5.487845 -8.945653)
					(end 5.381244 -9.028938)
				)
				(xy 2.548382 -11.8618) (xy 2.548382 -17.0434) (xy 3.132582 -17.6276) (xy 3.132582 -19.7104) (xy 3.970782 -20.5486)
				(xy 7.21106 -20.5486) (xy 7.50316 -20.2565) (xy 7.50316 -16.223742) (xy 9.139682 -14.58722) (xy 9.139682 -11.204702)
				(xy 6.78942 -8.85444)
			)
		)
	)
	(zone
		(net "P12V")
		(layer "B.Cu")
		(hatch none 0.5)
		(connect_pads
			(clearance 0.5)
		)
		(min_thickness 0.25)
		(fill yes
			(thermal_gap 0.5)
			(thermal_bridge_width 0.5)
			(island_removal_mode 0)
		)
		(polygon
			(pts
				(xy 87.104982 -6.2992) (xy 86.723982 -6.6802) (xy 86.723982 -8.69442) (xy 85.555582 -9.86282) (xy 85.555582 -16.1544)
				(xy 85.555582 -23.876) (xy 86.012782 -24.3332) (xy 92.337382 -24.3332) (xy 93.581982 -23.0886) (xy 93.581982 -17.44726)
				(xy 93.155262 -17.02054) (xy 89.9033 -17.02054) (xy 88.86698 -15.98422) (xy 88.86698 -7.66826) (xy 88.888316 -7.646924)
				(xy 88.887808 -7.599934) (xy 88.887808 -6.2992)
			)
		)
	)
	(zone
		(net "P12V")
		(layer "In1.Cu")
		(hatch none 0.5)
		(connect_pads
			(clearance 0.5)
		)
		(min_thickness 0.25)
		(fill yes
			(thermal_gap 0.5)
			(thermal_bridge_width 0.5)
			(island_removal_mode 0)
		)
		(polygon
			(pts
				(xy 79.212948 -5.588) (xy 79.212948 -7.450074) (xy 79.211932 -7.509002) (xy 79.211932 -7.765796)
				(arc
					(start 79.176626 -7.801102)
					(mid 78.982861 -8.307646)
					(end 78.640432 -8.728202)
				)
				(xy 78.640432 -9.82091)
				(arc
					(start 78.692248 -9.872726)
					(mid 78.765837 -9.859605)
					(end 78.840076 -9.850882)
				)
				(xy 78.844902 -9.846056) (xy 82.055208 -9.846056)
				(arc
					(start 82.060034 -9.850882)
					(mid 82.836767 -10.213339)
					(end 83.199224 -10.990072)
				)
				(xy 83.20405 -10.994898) (xy 83.20405 -14.100048) (xy 83.20405 -14.205204)
				(arc
					(start 83.199224 -14.21003)
					(mid 82.836767 -14.986763)
					(end 82.060034 -15.34922)
				)
				(xy 82.055208 -15.354046) (xy 79.140558 -15.354046) (xy 79.140558 -17.039082) (xy 80.132682 -18.031206)
				(xy 80.132682 -19.233134) (xy 79.464916 -19.9009) (xy 10.394188 -19.9009) (xy 9.825482 -19.332194)
				(xy 9.825482 -18.189194) (xy 8.809482 -17.173194) (xy 8.809482 -11.328908)
				(arc
					(start 5.907278 -8.42645)
					(mid 5.404585 -9.012764)
					(end 4.699508 -9.327896)
				)
				(xy 4.665726 -9.361932) (xy 4.409948 -9.361932) (xy 4.350004 -9.362948)
				(arc
					(start 0.999998 -9.362948)
					(mid 0.832426 -9.432358)
					(end 0.763016 -9.59993)
				)
				(arc
					(start 0.763016 -26.100024)
					(mid 0.832426 -26.267596)
					(end 0.999998 -26.337006)
				)
				(arc
					(start 36.500054 -26.337006)
					(mid 36.667626 -26.267596)
					(end 36.737036 -26.100024)
				)
				(arc
					(start 36.737036 -26.100024)
					(mid 37.135422 -24.983777)
					(end 38.150546 -24.372062)
				)
				(xy 38.184328 -24.338026) (xy 38.440106 -24.338026) (xy 38.50005 -24.33701) (xy 56.500014 -24.33701)
				(xy 56.559958 -24.338026) (xy 56.815736 -24.338026)
				(arc
					(start 56.849518 -24.372062)
					(mid 57.864595 -24.983815)
					(end 58.263028 -26.100024)
				)
				(arc
					(start 58.263028 -26.100024)
					(mid 58.332438 -26.267596)
					(end 58.50001 -26.337006)
				)
				(arc
					(start 94.000066 -26.337006)
					(mid 94.167638 -26.267596)
					(end 94.237048 -26.100024)
				)
				(arc
					(start 94.237048 -17.22501)
					(mid 94.167638 -17.057438)
					(end 94.000066 -16.988028)
				)
				(xy 90.65006 -16.988028) (xy 90.590116 -16.987012) (xy 90.334338 -16.987012)
				(arc
					(start 90.300556 -16.952976)
					(mid 89.403463 -16.471611)
					(end 88.922098 -15.574518)
				)
				(xy 88.888062 -15.540736) (xy 88.888062 -15.284958) (xy 88.887046 -15.225014) (xy 88.887046 -5.588)
			)
		)
	)
	(zone
		(net "GND")
		(layer "In1.Cu")
		(hatch none 0.5)
		(connect_pads
			(clearance 0.5)
		)
		(min_thickness 0.25)
		(fill yes
			(thermal_gap 0.5)
			(thermal_bridge_width 0.5)
			(island_removal_mode 0)
		)
		(polygon
			(pts
				(xy 6.113018 -5.588) (xy 6.113018 -7.599934) (xy 6.112002 -7.659878) (xy 6.112002 -7.915656)
				(arc
					(start 6.077966 -7.949438)
					(mid 6.068376 -7.993892)
					(end 6.057646 -8.038084)
				)
				(xy 9.190482 -11.17092) (xy 9.190482 -17.015206) (xy 10.206482 -18.031206) (xy 10.206482 -19.174206)
				(xy 10.552176 -19.5199) (xy 79.306928 -19.5199) (xy 79.751682 -19.075146) (xy 79.751682 -18.189194)
				(xy 79.593948 -18.031206) (xy 78.759558 -17.19707)
				(arc
					(start 78.759558 -15.339568)
					(mid 78.035086 -14.957676)
					(end 77.700886 -14.21003)
				)
				(xy 77.69606 -14.205204) (xy 77.69606 -10.994898)
				(arc
					(start 77.700886 -10.990072)
					(mid 77.887076 -10.434775)
					(end 78.305152 -10.024618)
				)
				(xy 78.259432 -9.978898)
				(arc
					(start 78.259432 -8.985504)
					(mid 76.750968 -8.990632)
					(end 75.823318 -7.801102)
				)
				(xy 75.788012 -7.765796) (xy 75.788012 -7.509002) (xy 75.786996 -7.450074) (xy 75.786996 -5.588)
			)
		)
		(polygon
			(pts
				(xy 75.455018 -9.846056) (xy 72.244712 -9.846056)
				(arc
					(start 72.239886 -9.850882)
					(mid 71.463153 -10.213339)
					(end 71.100696 -10.990072)
				)
				(xy 71.09587 -10.994898) (xy 71.09587 -14.100048) (xy 71.09587 -14.205204)
				(arc
					(start 71.100696 -14.21003)
					(mid 71.463153 -14.986763)
					(end 72.239886 -15.34922)
				)
				(xy 72.244712 -15.354046) (xy 75.455018 -15.354046)
				(arc
					(start 75.459844 -15.34922)
					(mid 76.236577 -14.986763)
					(end 76.599034 -14.21003)
				)
				(xy 76.60386 -14.205204) (xy 76.60386 -10.994898)
				(arc
					(start 76.599034 -10.990072)
					(mid 76.236577 -10.213339)
					(end 75.459844 -9.850882)
				)
			)
		)
		(polygon
			(pts
				(xy 68.855082 -15.354046)
				(arc
					(start 68.859908 -15.34922)
					(mid 69.636641 -14.986763)
					(end 69.999098 -14.21003)
				)
				(xy 70.003924 -14.205204) (xy 70.003924 -10.994898)
				(arc
					(start 69.999098 -10.990072)
					(mid 69.636641 -10.213339)
					(end 68.859908 -9.850882)
				)
				(xy 68.855082 -9.846056) (xy 65.644776 -9.846056)
				(arc
					(start 65.63995 -9.850882)
					(mid 64.863217 -10.213339)
					(end 64.50076 -10.990072)
				)
				(xy 64.495934 -10.994898) (xy 64.495934 -14.205204)
				(arc
					(start 64.50076 -14.21003)
					(mid 64.863217 -14.986763)
					(end 65.63995 -15.34922)
				)
				(xy 65.644776 -15.354046)
			)
		)
	)
	(zone
		(net "GND")
		(layer "In2.Cu")
		(hatch none 0.5)
		(connect_pads
			(clearance 0.5)
		)
		(min_thickness 0.25)
		(fill yes
			(thermal_gap 0.5)
			(thermal_bridge_width 0.5)
			(island_removal_mode 0)
		)
		(polygon
			(pts
				(xy 6.113018 -5.588) (xy 6.113018 -7.599934) (xy 6.112002 -7.659878) (xy 6.112002 -7.915656)
				(arc
					(start 6.077966 -7.949438)
					(mid 5.596601 -8.846531)
					(end 4.699508 -9.327896)
				)
				(xy 4.665726 -9.361932) (xy 4.409948 -9.361932) (xy 4.350004 -9.362948)
				(arc
					(start 0.999998 -9.362948)
					(mid 0.832426 -9.432358)
					(end 0.763016 -9.59993)
				)
				(arc
					(start 0.763016 -26.100024)
					(mid 0.832426 -26.267596)
					(end 0.999998 -26.337006)
				)
				(arc
					(start 36.500054 -26.337006)
					(mid 36.667626 -26.267596)
					(end 36.737036 -26.100024)
				)
				(arc
					(start 36.737036 -26.100024)
					(mid 37.135422 -24.983777)
					(end 38.150546 -24.372062)
				)
				(xy 38.184328 -24.338026) (xy 38.440106 -24.338026) (xy 38.50005 -24.33701) (xy 56.500014 -24.33701)
				(xy 56.559958 -24.338026) (xy 56.815736 -24.338026)
				(arc
					(start 56.849518 -24.372062)
					(mid 57.864595 -24.983815)
					(end 58.263028 -26.100024)
				)
				(arc
					(start 58.263028 -26.100024)
					(mid 58.332438 -26.267596)
					(end 58.50001 -26.337006)
				)
				(arc
					(start 94.000066 -26.337006)
					(mid 94.167638 -26.267596)
					(end 94.237048 -26.100024)
				)
				(arc
					(start 94.237048 -17.22501)
					(mid 94.167638 -17.057438)
					(end 94.000066 -16.988028)
				)
				(xy 90.65006 -16.988028) (xy 90.590116 -16.987012) (xy 90.334338 -16.987012)
				(arc
					(start 90.300556 -16.952976)
					(mid 89.403463 -16.471611)
					(end 88.922098 -15.574518)
				)
				(xy 88.888062 -15.540736) (xy 88.888062 -15.284958) (xy 88.887046 -15.225014) (xy 88.887046 -5.588)
				(xy 79.212948 -5.588) (xy 79.212948 -7.450074) (xy 79.211932 -7.509002) (xy 79.211932 -7.765796)
				(arc
					(start 79.176626 -7.801102)
					(mid 77.499972 -9.16308)
					(end 75.823318 -7.801102)
				)
				(xy 75.788012 -7.765796) (xy 75.788012 -7.509002) (xy 75.786996 -7.450074) (xy 75.786996 -5.588)
			)
		)
		(polygon
			(pts
				(xy 82.055208 -9.846056) (xy 78.844902 -9.846056)
				(arc
					(start 78.840076 -9.850882)
					(mid 78.063343 -10.213339)
					(end 77.700886 -10.990072)
				)
				(xy 77.69606 -10.994898) (xy 77.69606 -14.205204)
				(arc
					(start 77.700886 -14.21003)
					(mid 78.063343 -14.986763)
					(end 78.840076 -15.34922)
				)
				(xy 78.844902 -15.354046) (xy 82.055208 -15.354046)
				(arc
					(start 82.060034 -15.34922)
					(mid 82.836767 -14.986763)
					(end 83.199224 -14.21003)
				)
				(xy 83.20405 -14.205204) (xy 83.20405 -14.100048) (xy 83.20405 -10.994898)
				(arc
					(start 83.199224 -10.990072)
					(mid 82.836767 -10.213339)
					(end 82.060034 -9.850882)
				)
			)
		)
		(polygon
			(pts
				(xy 75.455018 -9.846056) (xy 72.244712 -9.846056)
				(arc
					(start 72.239886 -9.850882)
					(mid 71.463153 -10.213339)
					(end 71.100696 -10.990072)
				)
				(xy 71.09587 -10.994898) (xy 71.09587 -14.100048) (xy 71.09587 -14.205204)
				(arc
					(start 71.100696 -14.21003)
					(mid 71.463153 -14.986763)
					(end 72.239886 -15.34922)
				)
				(xy 72.244712 -15.354046) (xy 75.455018 -15.354046)
				(arc
					(start 75.459844 -15.34922)
					(mid 76.236577 -14.986763)
					(end 76.599034 -14.21003)
				)
				(xy 76.60386 -14.205204) (xy 76.60386 -10.994898)
				(arc
					(start 76.599034 -10.990072)
					(mid 76.236577 -10.213339)
					(end 75.459844 -9.850882)
				)
			)
		)
		(polygon
			(pts
				(xy 68.855082 -15.354046)
				(arc
					(start 68.859908 -15.34922)
					(mid 69.636641 -14.986763)
					(end 69.999098 -14.21003)
				)
				(xy 70.003924 -14.205204) (xy 70.003924 -10.994898)
				(arc
					(start 69.999098 -10.990072)
					(mid 69.636641 -10.213339)
					(end 68.859908 -9.850882)
				)
				(xy 68.855082 -9.846056) (xy 65.644776 -9.846056)
				(arc
					(start 65.63995 -9.850882)
					(mid 64.863217 -10.213339)
					(end 64.50076 -10.990072)
				)
				(xy 64.495934 -10.994898) (xy 64.495934 -14.205204)
				(arc
					(start 64.50076 -14.21003)
					(mid 64.863217 -14.986763)
					(end 65.63995 -15.34922)
				)
				(xy 65.644776 -15.354046)
			)
		)
	)
)
